G04 ================== begin FILE IDENTIFICATION RECORD ==================*
G04 Layout Name:  D:/<user>/Wistron_project/16317-1/gbr/16317-1.brd*
G04 Film Name:    L5VCC*
G04 File Format:  Gerber RS274X*
G04 File Origin:  Cadence Allegro 16.5-S056*
G04 Origin Date:  Fri Jun 09 15:53:33 2017*
G04 *
G04 Layer:  VIA CLASS/L5VCC*
G04 Layer:  PIN/L5VCC*
G04 Layer:  PACKAGE GEOMETRY/PWRVCC*
G04 Layer:  ETCH/L5VCC*
G04 Layer:  DRAWING FORMAT/LAYER_PCB_STORY*
G04 Layer:  DRAWING FORMAT/LAYER_L5VCC*
G04 *
G04 Offset:    (0.00 0.00)*
G04 Mirror:    No*
G04 Mode:      Negative*
G04 Rotation:  0*
G04 FullContactRelief:  No*
G04 UndefLineWidth:     6.00*
G04 ================== end FILE IDENTIFICATION RECORD ====================*
%FSLAX35Y35*MOIN*%
%IR0*IPPOS*OFA0.00000B0.00000*MIA0B0*SFA1.00000B1.00000*%
%ADD34C,.03*%
%ADD36C,.04*%
%ADD12C,.032*%
%ADD33C,.043*%
%ADD22C,.081*%
%ADD16C,.063*%
%ADD15C,.036*%
%ADD19C,.065*%
%ADD17C,.038*%
%ADD35C,.058*%
%AMMACRO18*
4,1,15,.00398,.00044,
.003999,.000208,
.004004,-.000025,
.003996,-.000258,
.00398,-.00044,
.00483,-.00129,
.004897,-.001007,
.004947,-.000721,
.004981,-.000432,
.004997,-.000141,
.004997,.000149,
.00498,.00044,
.004946,.000729,
.004895,.001015,
.00483,.00129,
.00398,.00044,
90.*
4,1,15,.00044,-.00398,
.000208,-.003999,
-.000025,-.004004,
-.000258,-.003996,
-.00044,-.00398,
-.00129,-.00483,
-.001007,-.004897,
-.000721,-.004947,
-.000432,-.004981,
-.000141,-.004997,
.000149,-.004997,
.00044,-.00498,
.000729,-.004946,
.001015,-.004895,
.00129,-.00483,
.00044,-.00398,
90.*
4,1,15,-.00398,-.00044,
-.003999,-.000208,
-.004004,.000025,
-.003996,.000258,
-.00398,.00044,
-.00483,.00129,
-.004897,.001007,
-.004947,.000721,
-.004981,.000432,
-.004997,.000141,
-.004997,-.000149,
-.00498,-.00044,
-.004946,-.000729,
-.004895,-.001015,
-.00483,-.00129,
-.00398,-.00044,
90.*
4,1,15,-.00044,.00398,
-.000208,.003999,
.000025,.004004,
.000258,.003996,
.00044,.00398,
.00129,.00483,
.001007,.004897,
.000721,.004947,
.000432,.004981,
.000141,.004997,
-.000149,.004997,
-.00044,.00498,
-.000729,.004946,
-.001015,.004895,
-.00129,.00483,
-.00044,.00398,
90.*
%
%ADD18MACRO18*%
%AMMACRO28*
4,1,15,-.00398,.00044,
-.003999,.000208,
-.004004,-.000025,
-.003996,-.000258,
-.00398,-.00044,
-.00483,-.00129,
-.004897,-.001007,
-.004947,-.000721,
-.004981,-.000432,
-.004997,-.000141,
-.004997,.000149,
-.00498,.00044,
-.004946,.000729,
-.004895,.001015,
-.00483,.00129,
-.00398,.00044,
90.*
4,1,15,-.00044,-.00398,
-.000208,-.003999,
.000025,-.004004,
.000258,-.003996,
.00044,-.00398,
.00129,-.00483,
.001007,-.004897,
.000721,-.004947,
.000432,-.004981,
.000141,-.004997,
-.000149,-.004997,
-.00044,-.00498,
-.000729,-.004946,
-.001015,-.004895,
-.00129,-.00483,
-.00044,-.00398,
90.*
4,1,15,.00398,-.00044,
.003999,-.000208,
.004004,.000025,
.003996,.000258,
.00398,.00044,
.00483,.00129,
.004897,.001007,
.004947,.000721,
.004981,.000432,
.004997,.000141,
.004997,-.000149,
.00498,-.00044,
.004946,-.000729,
.004895,-.001015,
.00483,-.00129,
.00398,-.00044,
90.*
4,1,15,.00044,.00398,
.000208,.003999,
-.000025,.004004,
-.000258,.003996,
-.00044,.00398,
-.00129,.00483,
-.001007,.004897,
-.000721,.004947,
-.000432,.004981,
-.000141,.004997,
.000149,.004997,
.00044,.00498,
.000729,.004946,
.001015,.004895,
.00129,.00483,
.00044,.00398,
90.*
%
%ADD28MACRO28*%
%AMMACRO11*
4,1,15,.00398,.00044,
.003999,.000208,
.004004,-.000025,
.003996,-.000258,
.00398,-.00044,
.00483,-.00129,
.004897,-.001007,
.004947,-.000721,
.004981,-.000432,
.004997,-.000141,
.004997,.000149,
.00498,.00044,
.004946,.000729,
.004895,.001015,
.00483,.00129,
.00398,.00044,
0.0*
4,1,15,.00044,-.00398,
.000208,-.003999,
-.000025,-.004004,
-.000258,-.003996,
-.00044,-.00398,
-.00129,-.00483,
-.001007,-.004897,
-.000721,-.004947,
-.000432,-.004981,
-.000141,-.004997,
.000149,-.004997,
.00044,-.00498,
.000729,-.004946,
.001015,-.004895,
.00129,-.00483,
.00044,-.00398,
0.0*
4,1,15,-.00398,-.00044,
-.003999,-.000208,
-.004004,.000025,
-.003996,.000258,
-.00398,.00044,
-.00483,.00129,
-.004897,.001007,
-.004947,.000721,
-.004981,.000432,
-.004997,.000141,
-.004997,-.000149,
-.00498,-.00044,
-.004946,-.000729,
-.004895,-.001015,
-.00483,-.00129,
-.00398,-.00044,
0.0*
4,1,15,-.00044,.00398,
-.000208,.003999,
.000025,.004004,
.000258,.003996,
.00044,.00398,
.00129,.00483,
.001007,.004897,
.000721,.004947,
.000432,.004981,
.000141,.004997,
-.000149,.004997,
-.00044,.00498,
-.000729,.004946,
-.001015,.004895,
-.00129,.00483,
-.00044,.00398,
0.0*
%
%ADD11MACRO11*%
%AMMACRO14*
4,1,15,-.00398,.00044,
-.003999,.000208,
-.004004,-.000025,
-.003996,-.000258,
-.00398,-.00044,
-.00483,-.00129,
-.004897,-.001007,
-.004947,-.000721,
-.004981,-.000432,
-.004997,-.000141,
-.004997,.000149,
-.00498,.00044,
-.004946,.000729,
-.004895,.001015,
-.00483,.00129,
-.00398,.00044,
0.0*
4,1,15,-.00044,-.00398,
-.000208,-.003999,
.000025,-.004004,
.000258,-.003996,
.00044,-.00398,
.00129,-.00483,
.001007,-.004897,
.000721,-.004947,
.000432,-.004981,
.000141,-.004997,
-.000149,-.004997,
-.00044,-.00498,
-.000729,-.004946,
-.001015,-.004895,
-.00129,-.00483,
-.00044,-.00398,
0.0*
4,1,15,.00398,-.00044,
.003999,-.000208,
.004004,.000025,
.003996,.000258,
.00398,.00044,
.00483,.00129,
.004897,.001007,
.004947,.000721,
.004981,.000432,
.004997,.000141,
.004997,-.000149,
.00498,-.00044,
.004946,-.000729,
.004895,-.001015,
.00483,-.00129,
.00398,-.00044,
0.0*
4,1,15,.00044,.00398,
.000208,.003999,
-.000025,.004004,
-.000258,.003996,
-.00044,.00398,
-.00129,.00483,
-.001007,.004897,
-.000721,.004947,
-.000432,.004981,
-.000141,.004997,
.000149,.004997,
.00044,.00498,
.000729,.004946,
.001015,.004895,
.00129,.00483,
.00044,.00398,
0.0*
%
%ADD14MACRO14*%
%ADD26C,.111*%
%ADD10C,.114*%
%ADD31C,.432*%
%ADD20C,.18*%
%ADD30C,.127*%
%ADD29C,.154*%
%ADD27C,.147*%
%ADD37C,.166*%
%ADD23C,.139*%
%AMMACRO21*
4,1,15,.00398,.00044,
.003999,.000208,
.004004,-.000025,
.003996,-.000258,
.00398,-.00044,
.00483,-.00129,
.004897,-.001007,
.004947,-.000721,
.004981,-.000432,
.004997,-.000141,
.004997,.000149,
.00498,.00044,
.004946,.000729,
.004895,.001015,
.00483,.00129,
.00398,.00044,
270.*
4,1,15,.00044,-.00398,
.000208,-.003999,
-.000025,-.004004,
-.000258,-.003996,
-.00044,-.00398,
-.00129,-.00483,
-.001007,-.004897,
-.000721,-.004947,
-.000432,-.004981,
-.000141,-.004997,
.000149,-.004997,
.00044,-.00498,
.000729,-.004946,
.001015,-.004895,
.00129,-.00483,
.00044,-.00398,
270.*
4,1,15,-.00398,-.00044,
-.003999,-.000208,
-.004004,.000025,
-.003996,.000258,
-.00398,.00044,
-.00483,.00129,
-.004897,.001007,
-.004947,.000721,
-.004981,.000432,
-.004997,.000141,
-.004997,-.000149,
-.00498,-.00044,
-.004946,-.000729,
-.004895,-.001015,
-.00483,-.00129,
-.00398,-.00044,
270.*
4,1,15,-.00044,.00398,
-.000208,.003999,
.000025,.004004,
.000258,.003996,
.00044,.00398,
.00129,.00483,
.001007,.004897,
.000721,.004947,
.000432,.004981,
.000141,.004997,
-.000149,.004997,
-.00044,.00498,
-.000729,.004946,
-.001015,.004895,
-.00129,.00483,
-.00044,.00398,
270.*
%
%ADD21MACRO21*%
%AMMACRO13*
4,1,15,.00398,.00044,
.003999,.000208,
.004004,-.000025,
.003996,-.000258,
.00398,-.00044,
.00483,-.00129,
.004897,-.001007,
.004947,-.000721,
.004981,-.000432,
.004997,-.000141,
.004997,.000149,
.00498,.00044,
.004946,.000729,
.004895,.001015,
.00483,.00129,
.00398,.00044,
180.*
4,1,15,.00044,-.00398,
.000208,-.003999,
-.000025,-.004004,
-.000258,-.003996,
-.00044,-.00398,
-.00129,-.00483,
-.001007,-.004897,
-.000721,-.004947,
-.000432,-.004981,
-.000141,-.004997,
.000149,-.004997,
.00044,-.00498,
.000729,-.004946,
.001015,-.004895,
.00129,-.00483,
.00044,-.00398,
180.*
4,1,15,-.00398,-.00044,
-.003999,-.000208,
-.004004,.000025,
-.003996,.000258,
-.00398,.00044,
-.00483,.00129,
-.004897,.001007,
-.004947,.000721,
-.004981,.000432,
-.004997,.000141,
-.004997,-.000149,
-.00498,-.00044,
-.004946,-.000729,
-.004895,-.001015,
-.00483,-.00129,
-.00398,-.00044,
180.*
4,1,15,-.00044,.00398,
-.000208,.003999,
.000025,.004004,
.000258,.003996,
.00044,.00398,
.00129,.00483,
.001007,.004897,
.000721,.004947,
.000432,.004981,
.000141,.004997,
-.000149,.004997,
-.00044,.00498,
-.000729,.004946,
-.001015,.004895,
-.00129,.00483,
-.00044,.00398,
180.*
%
%ADD13MACRO13*%
%AMMACRO32*
4,1,15,-.00398,.00044,
-.003999,.000208,
-.004004,-.000025,
-.003996,-.000258,
-.00398,-.00044,
-.00483,-.00129,
-.004897,-.001007,
-.004947,-.000721,
-.004981,-.000432,
-.004997,-.000141,
-.004997,.000149,
-.00498,.00044,
-.004946,.000729,
-.004895,.001015,
-.00483,.00129,
-.00398,.00044,
180.*
4,1,15,-.00044,-.00398,
-.000208,-.003999,
.000025,-.004004,
.000258,-.003996,
.00044,-.00398,
.00129,-.00483,
.001007,-.004897,
.000721,-.004947,
.000432,-.004981,
.000141,-.004997,
-.000149,-.004997,
-.00044,-.00498,
-.000729,-.004946,
-.001015,-.004895,
-.00129,-.00483,
-.00044,-.00398,
180.*
4,1,15,.00398,-.00044,
.003999,-.000208,
.004004,.000025,
.003996,.000258,
.00398,.00044,
.00483,.00129,
.004897,.001007,
.004947,.000721,
.004981,.000432,
.004997,.000141,
.004997,-.000149,
.00498,-.00044,
.004946,-.000729,
.004895,-.001015,
.00483,-.00129,
.00398,-.00044,
180.*
4,1,15,.00044,.00398,
.000208,.003999,
-.000025,.004004,
-.000258,.003996,
-.00044,.00398,
-.00129,.00483,
-.001007,.004897,
-.000721,.004947,
-.000432,.004981,
-.000141,.004997,
.000149,.004997,
.00044,.00498,
.000729,.004946,
.001015,.004895,
.00129,.00483,
.00044,.00398,
180.*
%
%ADD32MACRO32*%
%AMMACRO25*
4,1,15,-.00398,.00044,
-.003999,.000208,
-.004004,-.000025,
-.003996,-.000258,
-.00398,-.00044,
-.00483,-.00129,
-.004897,-.001007,
-.004947,-.000721,
-.004981,-.000432,
-.004997,-.000141,
-.004997,.000149,
-.00498,.00044,
-.004946,.000729,
-.004895,.001015,
-.00483,.00129,
-.00398,.00044,
270.*
4,1,15,-.00044,-.00398,
-.000208,-.003999,
.000025,-.004004,
.000258,-.003996,
.00044,-.00398,
.00129,-.00483,
.001007,-.004897,
.000721,-.004947,
.000432,-.004981,
.000141,-.004997,
-.000149,-.004997,
-.00044,-.00498,
-.000729,-.004946,
-.001015,-.004895,
-.00129,-.00483,
-.00044,-.00398,
270.*
4,1,15,.00398,-.00044,
.003999,-.000208,
.004004,.000025,
.003996,.000258,
.00398,.00044,
.00483,.00129,
.004897,.001007,
.004947,.000721,
.004981,.000432,
.004997,.000141,
.004997,-.000149,
.00498,-.00044,
.004946,-.000729,
.004895,-.001015,
.00483,-.00129,
.00398,-.00044,
270.*
4,1,15,.00044,.00398,
.000208,.003999,
-.000025,.004004,
-.000258,.003996,
-.00044,.00398,
-.00129,.00483,
-.001007,.004897,
-.000721,.004947,
-.000432,.004981,
-.000141,.004997,
.000149,.004997,
.00044,.00498,
.000729,.004946,
.001015,.004895,
.00129,.00483,
.00044,.00398,
270.*
%
%ADD25MACRO25*%
%ADD38C,.02*%
%ADD39C,.006*%
%ADD55O,.10334X.04822*%
%ADD44C,.06104*%
%ADD49C,.0824*%
%ADD42C,.07704*%
%ADD47O,.515X.315*%
%ADD41C,.11004*%
%ADD45C,.14304*%
%ADD40C,.12504*%
%ADD50C,.13504*%
%ADD43C,.37504*%
%ADD51C,.29531*%
%ADD48O,.55202X.78802*%
%ADD53O,.09834X.04322*%
%ADD46O,.55204X.78804*%
%ADD54O,.09836X.04324*%
%ADD52O,.09854X.04342*%
G75*
%LPD*%
G75*
G36*
G01X-6000Y-6000D02*
X1940843D01*
Y1525685D01*
X-6000D01*
Y-6000D01*
G37*
%LPC*%
G75*
G36*
G01X102441Y1514685D02*
X279646D01*
Y1500000D01*
G03X288583Y1491063I8937J0D01*
G01X493307D01*
G03X502244Y1500000I0J8937D01*
G01Y1514685D01*
X679449D01*
Y1509055D01*
G03X688386Y1500118I8937J0D01*
G01X713976D01*
G03X722913Y1509055I0J8937D01*
G01Y1514685D01*
X774528D01*
Y1500000D01*
G03X783465Y1491063I8937J0D01*
G01X988189D01*
G03X997126Y1500000I0J8937D01*
G01Y1514685D01*
X1058756D01*
X1067638Y1505803D01*
Y1421260D01*
G03X1076575Y1412323I8937J0D01*
G01X1085630D01*
G03X1094567Y1421260I0J8937D01*
G01Y1505803D01*
X1103449Y1514685D01*
X1206220D01*
Y1509055D01*
G03X1215157Y1500118I8937J0D01*
G01X1240748D01*
G03X1249685Y1509055I0J8937D01*
G01Y1514685D01*
X1426890D01*
Y1500000D01*
G03X1435827Y1491063I8937J0D01*
G01X1640551D01*
G03X1649488Y1500000I0J8937D01*
G01Y1514685D01*
X1826693D01*
Y1509055D01*
G03X1835630Y1500118I8937J0D01*
G01X1861220D01*
G03X1870157Y1509055I0J8937D01*
G01Y1514685D01*
X1918031D01*
Y1464567D01*
G03X1926967Y1455630I8937J0D01*
G01X1929843D01*
Y5000D01*
X1229409D01*
Y185827D01*
G03X1220472Y194764I-8937J0D01*
G01X1064055D01*
Y244096D01*
G03X1063350Y247574I-8937J-1D01*
G01X1063297Y247698D01*
X1070338Y254740D01*
X1207577D01*
X1240852Y288014D01*
Y382950D01*
X1344789D01*
X1354950Y372789D01*
Y213011D01*
X1294250Y152311D01*
Y75189D01*
X1302089Y67350D01*
X1328642D01*
G02X1328956Y66703I0J-400D01*
G03X1362446Y55617I14745J-11585D01*
G02X1363129Y55910I400J11D01*
G01X1375325Y43714D01*
X1547775D01*
X1550427Y41062D01*
X1568184D01*
X1570872Y43750D01*
X1730811D01*
X1749811Y62750D01*
X1779811D01*
X1789811Y72750D01*
X1816311D01*
X1829811Y86250D01*
X1853689D01*
X1856689Y83250D01*
X1874689D01*
X1881750Y76189D01*
Y67189D01*
X1885689Y63250D01*
X1904311D01*
X1906250Y65189D01*
Y69311D01*
X1897250Y78311D01*
Y88311D01*
X1888250Y97311D01*
Y397011D01*
X1884250Y401011D01*
Y441089D01*
X1913250Y470089D01*
Y510311D01*
X1907311Y516250D01*
X1887311D01*
X1884750Y518811D01*
Y525189D01*
X1886750Y527189D01*
Y540311D01*
X1879811Y547250D01*
X1869311D01*
X1854611Y561950D01*
X1797889D01*
X1789250Y553311D01*
Y526311D01*
X1780189Y517250D01*
X1761311D01*
X1716611Y561950D01*
X1685389D01*
X1669750Y546311D01*
Y469311D01*
X1633689Y433250D01*
X1606181D01*
X1606130Y433374D01*
G03X1601870I-2130J-874D01*
G01X1601819Y433250D01*
X1554996D01*
G03X1552004I-1496J-1750D01*
G01X1485933D01*
G03X1482067I-1933J-1250D01*
G01X1240852D01*
Y437455D01*
X1294364Y490967D01*
Y676853D01*
G02X1294865Y677239I400J-1D01*
G03X1329472Y703937I7005J26698D01*
G01Y727537D01*
G03X1294865Y754235I-27602J0D01*
G02X1294363Y754622I-102J387D01*
G01Y940585D01*
X1297912Y944134D01*
Y1128917D01*
G02X1298363Y1129314I400J0D01*
G03X1329472Y1156692I3507J27378D01*
G01Y1180292D01*
G03X1298363Y1207670I-27602J0D01*
G02X1297912Y1208067I-51J397D01*
G01Y1255167D01*
X1271328Y1281752D01*
X975846D01*
X970252Y1287346D01*
Y1366846D01*
X898546Y1438552D01*
X807468D01*
X802398Y1433482D01*
Y1414252D01*
X651098D01*
Y1291748D01*
X802398D01*
Y1267891D01*
X759784Y1225276D01*
Y851982D01*
G02X759210Y851622I-400J0D01*
G03X719642Y826749I-11966J-24873D01*
G01Y803149D01*
G03X759210Y778276I27602J0D01*
G02X759784Y777916I174J-360D01*
G01Y489672D01*
X780112Y469344D01*
Y413636D01*
X829114Y364634D01*
X944069D01*
X990648Y318054D01*
Y253031D01*
X818897D01*
G03X809961Y244095I1J-8937D01*
G01Y194764D01*
X787402D01*
G03X778465Y185827I0J-8937D01*
G01Y5000D01*
X5000D01*
Y1455630D01*
X7874D01*
G03X16811Y1464567I0J8937D01*
G01Y1514685D01*
X58976D01*
Y1509055D01*
G03X67913Y1500118I8937J0D01*
G01X93504D01*
G03X97501Y1502114I0J5000D01*
G01X99134D01*
G03X102441Y1509055I-5630J6941D01*
G01Y1514685D01*
G37*
G36*
G01X803739Y1295750D02*
X655100D01*
Y1410250D01*
X803589D01*
X804900Y1408939D01*
Y1296911D01*
X803739Y1295750D01*
G37*
G36*
G01X1060873Y250933D02*
X1060733Y251046D01*
G03X1055118Y253031I-5616J-6952D01*
G01X994650D01*
Y319711D01*
X945726Y368635D01*
X830771D01*
X784113Y415293D01*
Y471001D01*
X763785Y491329D01*
Y781053D01*
G03X774846Y803149I-16541J22097D01*
G01Y826749D01*
G03X763785Y848845I-27602J-1D01*
G01Y1223619D01*
X806400Y1266234D01*
Y1431825D01*
X809125Y1434550D01*
X896889D01*
X966250Y1365189D01*
Y1285689D01*
X974189Y1277750D01*
X1269671D01*
X1293911Y1253510D01*
Y1206721D01*
G03X1274268Y1180292I7958J-26429D01*
G01Y1156692D01*
G03X1293911Y1130263I27601J0D01*
G01Y945791D01*
X1290362Y942242D01*
Y752625D01*
G03X1274268Y727537I11507J-25088D01*
G01Y703937D01*
G03X1290362Y678849I27601J0D01*
G01Y492624D01*
X1236850Y439112D01*
Y289671D01*
X1205920Y258741D01*
X1068680D01*
X1060873Y250933D01*
G37*
G36*
G01X1749189Y64250D02*
X1730189Y45250D01*
X1570250D01*
X1567562Y42562D01*
X1551049D01*
X1548397Y45214D01*
X1375947D01*
X1362015Y59146D01*
X1362002Y59203D01*
G03X1330932Y68850I-18301J-4085D01*
G01X1302711D01*
X1295750Y75811D01*
Y151689D01*
X1356450Y212389D01*
Y373411D01*
X1345411Y384450D01*
X1239969D01*
X1238350Y386069D01*
Y430305D01*
X1239795Y431750D01*
X1481706D01*
X1481736Y431586D01*
G03X1486264I2264J414D01*
G01X1486294Y431750D01*
X1601819D01*
X1601870Y431626D01*
G03X1606130I2130J874D01*
G01X1606181Y431750D01*
X1634311D01*
X1671250Y468689D01*
Y545689D01*
X1686011Y560450D01*
X1715989D01*
X1760689Y515750D01*
X1780811D01*
X1790750Y525689D01*
Y552689D01*
X1798511Y560450D01*
X1853989D01*
X1868689Y545750D01*
X1879189D01*
X1885250Y539689D01*
Y527811D01*
X1883250Y525811D01*
Y518189D01*
X1886689Y514750D01*
X1906689D01*
X1911750Y509689D01*
Y470711D01*
X1882750Y441711D01*
Y400389D01*
X1886750Y396389D01*
Y96689D01*
X1895750Y87689D01*
Y77689D01*
X1904750Y68689D01*
Y65811D01*
X1903689Y64750D01*
X1886311D01*
X1883250Y67811D01*
Y76811D01*
X1875311Y84750D01*
X1857311D01*
X1854311Y87750D01*
X1829189D01*
X1815689Y74250D01*
X1789189D01*
X1779189Y64250D01*
X1749189D01*
G37*
%LPD*%
G75*
G36*
G01X558368Y715747D02*
G02I-55121J0D01*
G37*
G36*
G01X715811Y84250D02*
X652697D01*
G03X652298Y83872I1J-400D01*
G02X649459Y81762I-2298J128D01*
G01X649350Y81789D01*
X636811Y69250D01*
X631311D01*
X629250Y67189D01*
Y64689D01*
X627811Y63250D01*
X621689D01*
X611189Y73750D01*
X576689D01*
X567489Y82950D01*
X531011D01*
X517311Y69250D01*
X505811D01*
X504750Y68189D01*
Y64689D01*
X503311Y63250D01*
X495689D01*
X485189Y73750D01*
X448189D01*
X439089Y82850D01*
X436356D01*
X436296Y82775D01*
G02X406950Y82850I-14643J11713D01*
G01X399911D01*
X385811Y68750D01*
X382311D01*
X380750Y67189D01*
Y64689D01*
X378811Y62750D01*
X371189D01*
X360189Y73750D01*
X328689D01*
X318189Y84250D01*
X293311D01*
X278311Y69250D01*
X257311D01*
X256250Y68189D01*
Y64689D01*
X254311Y62750D01*
X249689D01*
X246750Y65689D01*
Y79689D01*
X242189Y84250D01*
X162311D01*
X146811Y68750D01*
X133311D01*
X132250Y67689D01*
Y65189D01*
X130811Y63750D01*
X122689D01*
X112689Y73750D01*
X80689D01*
X68250Y86189D01*
Y397711D01*
X100289Y429750D01*
X120970D01*
G02X124630I1830J-1850D01*
G01X125770D01*
G02X129430I1830J-1850D01*
G01X205389D01*
X233989Y458350D01*
X245773D01*
X249374Y461951D01*
X268987D01*
X272588Y458350D01*
X426789D01*
X440750Y472311D01*
Y542311D01*
X448189Y549750D01*
X488811D01*
X495750Y542811D01*
Y518811D01*
X497811Y516750D01*
X501689D01*
X503250Y518311D01*
Y520811D01*
X505689Y523250D01*
X529189D01*
X555689Y549750D01*
X613811D01*
X620250Y543311D01*
Y518811D01*
X622811Y516250D01*
X626189D01*
X627750Y517811D01*
Y521811D01*
X628689Y522750D01*
X662689D01*
X689689Y549750D01*
X712811D01*
X721750Y540811D01*
Y406103D01*
G03X722508Y405925I400J0D01*
G02X774846Y393678I24736J-12247D01*
G01Y370078D01*
G02X767026Y350829I-27601J0D01*
G03X767312Y350150I286J-279D01*
G01X904911D01*
X921950Y333111D01*
Y308189D01*
X916411Y302650D01*
X886089D01*
X881650Y307089D01*
Y315589D01*
X878489Y318750D01*
X732611D01*
X721750Y307889D01*
Y90189D01*
X715811Y84250D01*
G37*
G36*
G01X1916450Y900777D02*
Y856789D01*
X1811702Y752041D01*
G03X1811784Y751412I282J-283D01*
G02X1825534Y727539I-13851J-23874D01*
G01Y703937D01*
G02X1770332I-27601J0D01*
G01Y709705D01*
G03X1769649Y709988I-400J0D01*
G01X1631750Y572089D01*
Y562311D01*
X1648250Y545811D01*
Y536311D01*
X1657750Y526811D01*
Y518189D01*
X1655311Y515750D01*
X1608689D01*
X1594189Y530250D01*
X1546811D01*
X1532311Y515750D01*
X1511689D01*
X1497189Y530250D01*
X1453989D01*
X1444789Y539450D01*
X1420511D01*
X1412250Y531189D01*
Y520189D01*
X1408311Y516250D01*
X1384689D01*
X1370689Y530250D01*
X1336689D01*
X1330250Y536689D01*
Y644504D01*
G02Y647496I1750J1496D01*
G01Y1009811D01*
X1334689Y1014250D01*
X1903611D01*
X1916450Y1001411D01*
Y903223D01*
G02Y900777I-1950J-1223D01*
G37*
G36*
G01X350414Y797736D02*
X350250Y797706D01*
Y532689D01*
X345311Y527750D01*
X327689D01*
X314589Y540850D01*
X308411D01*
X288811Y521250D01*
X257811D01*
X256250Y519689D01*
Y517689D01*
X254811Y516250D01*
X246689D01*
X237189Y525750D01*
X203689D01*
X194089Y535350D01*
X162911D01*
X149311Y521750D01*
X133311D01*
X132250Y520689D01*
Y517689D01*
X130811Y516250D01*
X122689D01*
X109689Y529250D01*
X74689D01*
X68750Y535189D01*
Y568189D01*
X61250Y575689D01*
Y902311D01*
X68250Y909311D01*
Y994311D01*
X76189Y1002250D01*
X713811D01*
X720750Y995311D01*
Y856589D01*
X703611Y839450D01*
X363311D01*
X350250Y826389D01*
Y802294D01*
X350414Y802264D01*
G02Y797736I-414J-2264D01*
G37*
G36*
G01X136894Y61269D02*
Y56768D01*
G02X133072Y56769I-1911J1D01*
G01Y61269D01*
G02X136894I1911J0D01*
G37*
G36*
G01Y514025D02*
Y509524D01*
G02X133072Y509525I-1911J1D01*
G01Y514025D01*
G02X136894I1911J0D01*
G37*
G36*
G01X261106Y61269D02*
Y56768D01*
G02X257284Y56769I-1911J1D01*
G01Y61269D01*
G02X261106I1911J0D01*
G37*
G36*
G01Y514025D02*
Y509524D01*
G02X257284Y509525I-1911J1D01*
G01Y514025D01*
G02X261106I1911J0D01*
G37*
G36*
G01X385320Y61269D02*
Y56768D01*
G02X381496Y56769I-1912J1D01*
G01Y61269D01*
G02X385320I1912J0D01*
G37*
G36*
G01X374502Y524075D02*
Y529076D01*
G02X378324Y529075I1911J-1D01*
G01Y524075D01*
G02X374502I-1911J0D01*
G37*
G36*
G01X385320Y514025D02*
Y509524D01*
G02X381496Y509525I-1912J1D01*
G01Y514025D01*
G02X385320I1912J0D01*
G37*
G36*
G01X636252Y1414252D02*
Y1291748D01*
X623752D01*
Y1287154D01*
X620846Y1284248D01*
X598154D01*
X593748Y1288654D01*
Y1300722D01*
X408680D01*
X401248Y1308154D01*
Y1364346D01*
X404748Y1367846D01*
Y1435479D01*
X408276Y1439006D01*
X431624D01*
X443109Y1427522D01*
X485893D01*
X499163Y1414252D01*
X636252D01*
G37*
G36*
G01X509532Y61269D02*
Y56768D01*
G02X505708Y56769I-1912J1D01*
G01Y61269D01*
G02X509532I1912J0D01*
G37*
G36*
G01X498714Y524075D02*
Y529076D01*
G02X502536Y529075I1911J-1D01*
G01Y524075D01*
G02X498714I-1911J0D01*
G37*
G36*
G01X633744Y61269D02*
Y56768D01*
G02X629922Y56769I-1911J1D01*
G01Y61269D01*
G02X633744I1911J0D01*
G37*
G36*
G01X622926Y524075D02*
Y529076D01*
G02X626750Y529075I1912J-1D01*
G01Y524075D01*
G02X622926I-1912J0D01*
G37*
G36*
G01X757958Y61269D02*
Y56768D01*
G02X754134Y56769I-1912J1D01*
G01Y61269D01*
G02X757958I1912J0D01*
G37*
G36*
G01X750962Y76319D02*
Y71318D01*
G02X747140Y71319I-1911J1D01*
G01Y76319D01*
G02X750962I1911J0D01*
G37*
G36*
G01X757958Y514025D02*
Y509524D01*
G02X754134Y509525I-1912J1D01*
G01Y514025D01*
G02X757958I1912J0D01*
G37*
G36*
G01X750962Y529075D02*
Y524074D01*
G02X747140Y524075I-1911J1D01*
G01Y529075D01*
G02X750962I1911J0D01*
G37*
G36*
G01Y981831D02*
Y976830D01*
G02X747140Y976831I-1911J1D01*
G01Y981831D01*
G02X750962I1911J0D01*
G37*
G36*
G01X754134Y962281D02*
Y966782D01*
G02X757958Y966781I1912J-1D01*
G01Y962281D01*
G02X754134I-1912J0D01*
G37*
G36*
G01X824610Y277165D02*
Y282678D01*
G02X828934Y282677I2162J-1D01*
G01Y277165D01*
G02X824610I-2162J0D01*
G37*
G36*
G01X852956D02*
Y282678D01*
G02X857280Y282677I2162J-1D01*
G01Y277165D01*
G02X852956I-2162J0D01*
G37*
G36*
G01X838784D02*
Y282678D01*
G02X843106Y282677I2161J-1D01*
G01Y277165D01*
G02X838784I-2161J0D01*
G37*
G36*
G01X860044Y258268D02*
Y263780D01*
G02X864366Y263779I2161J-1D01*
G01Y258268D01*
G02X860044I-2161J0D01*
G37*
G36*
G01X845870D02*
Y263780D01*
G02X850194Y263779I2162J-1D01*
G01Y258268D01*
G02X845870I-2162J0D01*
G37*
G36*
G01X831698D02*
Y263780D01*
G02X836020Y263779I2161J-1D01*
G01Y258268D01*
G02X831698I-2161J0D01*
G37*
G36*
G01X860044Y300787D02*
Y306300D01*
G02X864366Y306299I2161J-1D01*
G01Y300787D01*
G02X860044I-2161J0D01*
G37*
G36*
G01X845870D02*
Y306300D01*
G02X850194Y306299I2162J-1D01*
G01Y300787D01*
G02X845870I-2162J0D01*
G37*
G36*
G01X857280Y311023D02*
Y305511D01*
G02X852956Y305512I-2162J1D01*
G01Y311023D01*
G02X857280I2162J0D01*
G37*
G36*
G01X843106D02*
Y305511D01*
G02X838784Y305512I-2161J1D01*
G01Y311023D01*
G02X843106I2161J0D01*
G37*
G36*
G01X831698Y300787D02*
Y306300D01*
G02X836020Y306299I2161J-1D01*
G01Y300787D01*
G02X831698I-2161J0D01*
G37*
G36*
G01X828934Y311023D02*
Y305511D01*
G02X824610Y305512I-2162J1D01*
G01Y311023D01*
G02X828934I2162J0D01*
G37*
G36*
G01X824610Y291338D02*
Y296851D01*
G02X828934Y296850I2162J-1D01*
G01Y291338D01*
G02X824610I-2162J0D01*
G37*
G36*
G01X867130Y277165D02*
Y282678D01*
G02X871454Y282677I2162J-1D01*
G01Y277165D01*
G02X867130I-2162J0D01*
G37*
G36*
G01X878540Y263779D02*
Y258267D01*
G02X874216Y258268I-2162J1D01*
G01Y263779D01*
G02X878540I2162J0D01*
G37*
G36*
G01X874216Y300787D02*
Y306300D01*
G02X878540Y306299I2162J-1D01*
G01Y300787D01*
G02X874216I-2162J0D01*
G37*
G36*
G01X871454Y311023D02*
Y305511D01*
G02X867130Y305512I-2162J1D01*
G01Y311023D01*
G02X871454I2162J0D01*
G37*
G36*
G01X1270400Y70562D02*
X1275401D01*
G02X1275400Y66738I-1J-1912D01*
G01X1270400D01*
G02Y70562I0J1912D01*
G37*
G36*
G01X1261250Y51738D02*
X1256749D01*
G02X1256750Y55562I1J1912D01*
G01X1261250D01*
G02Y51738I0J-1912D01*
G37*
G36*
G01X1385463Y504494D02*
X1380962D01*
G02X1380963Y508318I1J1912D01*
G01X1385463D01*
G02Y504494I0J-1912D01*
G37*
G36*
G01X1509675D02*
X1505174D01*
G02X1505175Y508318I1J1912D01*
G01X1509675D01*
G02Y504494I0J-1912D01*
G37*
G36*
G01X1633888D02*
X1629387D01*
G02X1629388Y508318I1J1912D01*
G01X1633888D01*
G02Y504494I0J-1912D01*
G37*
G36*
G01X1758100Y51738D02*
X1753599D01*
G02X1753600Y55562I1J1912D01*
G01X1758100D01*
G02Y51738I0J-1912D01*
G37*
G36*
G01X1767250Y523318D02*
X1772251D01*
G02X1772250Y519494I-1J-1912D01*
G01X1767250D01*
G02Y523318I0J1912D01*
G37*
G36*
G01X1882313Y51738D02*
X1877812D01*
G02X1877813Y55562I1J1912D01*
G01X1882313D01*
G02Y51738I0J-1912D01*
G37*
G36*
G01X1896463Y519494D02*
X1891462D01*
G02X1891463Y523318I1J1912D01*
G01X1896463D01*
G02Y519494I0J-1912D01*
G37*
G36*
G01X1259402Y961861D02*
G02X1255578I-1912J0D01*
G01Y966362D01*
G02X1259402Y966361I1912J-1D01*
G01Y961861D01*
G37*
G36*
G01X1272064Y981831D02*
G02X1275886I1911J0D01*
G01Y976830D01*
G02X1272064Y976831I-1911J1D01*
G01Y981831D01*
G37*
G36*
G01X1270400Y519494D02*
G02Y523318I0J1912D01*
G01X1275401D01*
G02X1275400Y519494I-1J-1912D01*
G01X1270400D01*
G37*
G36*
G01X1261250Y508318D02*
G02Y504494I0J-1912D01*
G01X1256749D01*
G02X1256750Y508318I1J1912D01*
G01X1261250D01*
G37*
G36*
G01X1148652Y943346D02*
Y690154D01*
X1140946Y682448D01*
X1087354D01*
X1080348Y689454D01*
Y942841D01*
X1086959Y949452D01*
X1142546D01*
X1148652Y943346D01*
G37*
G36*
G01X1146452Y575946D02*
Y515854D01*
X1139546Y508948D01*
X1082854D01*
X1078348Y513454D01*
Y574746D01*
X1084954Y581352D01*
X1141046D01*
X1146452Y575946D01*
G37*
G36*
G01X1882313Y508318D02*
G02Y504494I0J-1912D01*
G01X1877812D01*
G02X1877813Y508318I1J1912D01*
G01X1882313D01*
G37*
G36*
G01X1896463Y70562D02*
G02Y66738I0J-1912D01*
G01X1891462D01*
G02X1891463Y70562I1J1912D01*
G01X1896463D01*
G37*
G36*
G01X1758100Y508318D02*
G02Y504494I0J-1912D01*
G01X1753599D01*
G02X1753600Y508318I1J1912D01*
G01X1758100D01*
G37*
G36*
G01X1767250Y66738D02*
G02Y70562I0J1912D01*
G01X1772251D01*
G02X1772250Y66738I-1J-1912D01*
G01X1767250D01*
G37*
G36*
G01X1633888Y55562D02*
G02Y51738I0J-1912D01*
G01X1629387D01*
G02X1629388Y55562I1J1912D01*
G01X1633888D01*
G37*
G36*
G01X1648038Y70562D02*
G02Y66738I0J-1912D01*
G01X1643037D01*
G02X1643038Y70562I1J1912D01*
G01X1648038D01*
G37*
G36*
G01X1518825Y66738D02*
G02Y70562I0J1912D01*
G01X1523826D01*
G02X1523825Y66738I-1J-1912D01*
G01X1518825D01*
G37*
G36*
G01X1509675Y55562D02*
G02Y51738I0J-1912D01*
G01X1505174D01*
G02X1505175Y55562I1J1912D01*
G01X1509675D01*
G37*
G36*
G01X1385463D02*
G02Y51738I0J-1912D01*
G01X1380962D01*
G02X1380963Y55562I1J1912D01*
G01X1385463D01*
G37*
G36*
G01X1399613Y70562D02*
G02Y66738I0J-1912D01*
G01X1394612D01*
G02X1394613Y70562I1J1912D01*
G01X1399613D01*
G37*
G36*
G01X1575626Y103397D02*
G02X1608421Y103767I16499J-8808D01*
G02X1575626Y103397I-16295J-9279D01*
G37*
G36*
G01X1729037Y262991D02*
G02I-55120J0D01*
G37*
G54D44*
X1902756Y39508D03*
X1778543D03*
X1654331Y492264D03*
Y39508D03*
X1530118Y492264D03*
Y39508D03*
X1405906Y492264D03*
Y39508D03*
X1281693D03*
X732087Y945020D03*
Y492264D03*
Y39508D03*
X607874D03*
X483661D03*
X359449Y492264D03*
Y39508D03*
X235236Y492264D03*
Y39508D03*
X111024Y492264D03*
Y39508D03*
X1281693Y492264D03*
Y945020D03*
X1778543Y492264D03*
X1902756D03*
G54D49*
X80709Y1485118D03*
X701181D03*
X1227953D03*
X1848425D03*
G54D42*
X1902756Y1093642D03*
Y640886D03*
Y188130D03*
X1778543Y1093642D03*
Y640886D03*
X1654331Y1093642D03*
X1530118D03*
X1405906D03*
X1281693Y188130D03*
X732087Y1093642D03*
Y640886D03*
Y188130D03*
X607874Y1093642D03*
Y640886D03*
X483661Y1093642D03*
Y640886D03*
X359449Y1093642D03*
Y640886D03*
X235236Y1093642D03*
X111024D03*
X1281693Y640886D03*
Y1093642D03*
X1405906Y188130D03*
X1530118D03*
X1654331D03*
X1778543D03*
G54D47*
X256535Y1320472D03*
G54D41*
X1869500Y1461500D03*
X63374Y1454500D03*
X59400Y32600D03*
G54D45*
X1761417Y1495669D03*
X1695275D03*
X1381102D03*
X1314960D03*
X614173D03*
X548031D03*
X233858D03*
X167716D03*
G54D40*
X1761417Y1466929D03*
Y1445275D03*
X1381102Y1466929D03*
Y1445275D03*
X614173D03*
X233858Y1466929D03*
Y1445275D03*
X614173Y1466929D03*
G54D50*
X1343701Y122046D03*
X1840551D03*
G54D43*
Y55118D03*
X670078D03*
X173228D03*
G54D51*
X1104527Y1162258D03*
G54D48*
X627263Y715737D03*
Y1168492D03*
X1549901D03*
X1797933D03*
X1181889Y972429D03*
Y381878D03*
X961417Y972429D03*
Y703925D03*
X1797933Y262980D03*
X1549901Y262981D03*
G54D46*
X131200Y1168492D03*
X379232Y715737D03*
Y1168492D03*
X1301870Y262980D03*
%LPC*%
G75*
G36*
G01X250311Y64250D02*
X248250Y66311D01*
Y80311D01*
X242811Y85750D01*
X161689D01*
X146189Y70250D01*
X132689D01*
X130750Y68311D01*
Y65811D01*
X130189Y65250D01*
X123311D01*
X113311Y75250D01*
X81311D01*
X69750Y86811D01*
Y397089D01*
X100911Y428250D01*
X206011D01*
X234611Y456850D01*
X246395D01*
X249996Y460451D01*
X268365D01*
X271966Y456850D01*
X427411D01*
X442250Y471689D01*
Y541689D01*
X448811Y548250D01*
X488189D01*
X494250Y542189D01*
Y518189D01*
X497189Y515250D01*
X502311D01*
X504750Y517689D01*
Y520189D01*
X506311Y521750D01*
X529811D01*
X556311Y548250D01*
X613189D01*
X618750Y542689D01*
Y518189D01*
X622189Y514750D01*
X626811D01*
X629250Y517189D01*
Y521189D01*
X629311Y521250D01*
X663311D01*
X690311Y548250D01*
X712189D01*
X720250Y540189D01*
Y399437D01*
G03X719642Y393678I26994J-5761D01*
G01Y370078D01*
G03X720246Y364339I27602J4D01*
G01X720250Y364319D01*
Y360889D01*
X721830Y359309D01*
X721845Y359273D01*
G03X736439Y344679I25399J10805D01*
G01X736475Y344664D01*
X736489Y344650D01*
X736508D01*
X736545Y344634D01*
G03X764642Y348650I10699J25444D01*
G01X904289D01*
X920450Y332489D01*
Y308811D01*
X915789Y304150D01*
X886711D01*
X883150Y307711D01*
Y316211D01*
X879111Y320250D01*
X731989D01*
X720250Y308511D01*
Y90811D01*
X715189Y85750D01*
X651496D01*
G03X648031Y82807I-1496J-1750D01*
G01X648112Y82673D01*
X636189Y70750D01*
X630689D01*
X627750Y67811D01*
Y65311D01*
X627189Y64750D01*
X622311D01*
X611811Y75250D01*
X577311D01*
X568111Y84450D01*
X530389D01*
X516689Y70750D01*
X505189D01*
X503250Y68811D01*
Y65311D01*
X502689Y64750D01*
X496311D01*
X485811Y75250D01*
X448811D01*
X439711Y84350D01*
X438144D01*
G02X437799Y84953I0J400D01*
G03X405507I-16146J9535D01*
G02X405162Y84350I-345J-203D01*
G01X399289D01*
X385189Y70250D01*
X381689D01*
X379250Y67811D01*
Y65311D01*
X378189Y64250D01*
X371811D01*
X360811Y75250D01*
X329311D01*
X318811Y85750D01*
X312847D01*
G03X310753I-1047J-2050D01*
G01X292689D01*
X277689Y70750D01*
X256689D01*
X254750Y68811D01*
Y65311D01*
X253689Y64250D01*
X250311D01*
G37*
G36*
G01X348750Y798067D02*
Y533311D01*
X344689Y529250D01*
X328311D01*
X315211Y542350D01*
X307789D01*
X288189Y522750D01*
X257189D01*
X254750Y520311D01*
Y518311D01*
X254189Y517750D01*
X247311D01*
X237811Y527250D01*
X204311D01*
X194711Y536850D01*
X162289D01*
X148689Y523250D01*
X132689D01*
X130750Y521311D01*
Y518311D01*
X130189Y517750D01*
X123311D01*
X110311Y530750D01*
X75311D01*
X70250Y535811D01*
Y568811D01*
X62750Y576311D01*
Y901689D01*
X69750Y908689D01*
Y993689D01*
X76811Y1000750D01*
X713189D01*
X719250Y994689D01*
Y857211D01*
X702989Y840950D01*
X362689D01*
X348750Y827011D01*
Y801933D01*
G03Y798067I1250J-1933D01*
G37*
G36*
G01X599811Y1288250D02*
X597750Y1290311D01*
Y1302811D01*
X595837Y1304724D01*
X536520D01*
G02X536396Y1305504I0J400D01*
G03X531496Y1336222I-4900J14968D01*
G01X511496D01*
G03X506596Y1305504I0J-15750D01*
G02X506472Y1304724I-124J-380D01*
G01X410337D01*
X405250Y1309811D01*
Y1362689D01*
X408750Y1366189D01*
Y1433822D01*
X409933Y1435005D01*
X429967D01*
X441452Y1423520D01*
X484236D01*
X497506Y1410250D01*
X632250D01*
Y1295750D01*
X621689D01*
X619750Y1293811D01*
Y1288811D01*
X619189Y1288250D01*
X599811D01*
G37*
G36*
G01X1137889Y512950D02*
X1084511D01*
X1082350Y515111D01*
Y573089D01*
X1086611Y577350D01*
X1139389D01*
X1142450Y574289D01*
Y517511D01*
X1137889Y512950D01*
G37*
G36*
G01X1139289Y686450D02*
X1089011D01*
X1084350Y691111D01*
Y941184D01*
X1088616Y945450D01*
X1140889D01*
X1144650Y941689D01*
Y691811D01*
X1139289Y686450D01*
G37*
G36*
G01X1914950Y857411D02*
X1809933Y752394D01*
G03X1770332Y727537I-11999J-24857D01*
G01Y712792D01*
X1705836Y648297D01*
X1705766Y648290D01*
G03X1703710Y646234I234J-2290D01*
G01X1703703Y646164D01*
X1630250Y572711D01*
Y561689D01*
X1646750Y545189D01*
Y535689D01*
X1656250Y526189D01*
Y518811D01*
X1654689Y517250D01*
X1609311D01*
X1594811Y531750D01*
X1546189D01*
X1531689Y517250D01*
X1512311D01*
X1497811Y531750D01*
X1454611D01*
X1445411Y540950D01*
X1419889D01*
X1410750Y531811D01*
Y520811D01*
X1407689Y517750D01*
X1385311D01*
X1371311Y531750D01*
X1337311D01*
X1331750Y537311D01*
Y1009189D01*
X1335311Y1012750D01*
X1902989D01*
X1914950Y1000789D01*
Y857411D01*
G37*
%LPD*%
G75*
G36*
G01X629922Y514025D02*
G02X633744I1911J0D01*
G01Y509524D01*
G02X629922Y509525I-1911J1D01*
G01Y514025D01*
G37*
G36*
G01X622926Y76319D02*
G02X626750I1912J0D01*
G01Y71318D01*
G02X622926Y71319I-1912J1D01*
G01Y76319D01*
G37*
G36*
G01X505708Y514025D02*
G02X509532I1912J0D01*
G01Y509524D01*
G02X505708Y509525I-1912J1D01*
G01Y514025D01*
G37*
G36*
G01X498714Y76319D02*
G02X502536I1911J0D01*
G01Y71318D01*
G02X498714Y71319I-1911J1D01*
G01Y76319D01*
G37*
G36*
G01X374502D02*
G02X378324I1911J0D01*
G01Y71318D01*
G02X374502Y71319I-1911J1D01*
G01Y76319D01*
G37*
G36*
G01X250288D02*
G02X254112I1912J0D01*
G01Y71318D01*
G02X250288Y71319I-1912J1D01*
G01Y76319D01*
G37*
G36*
G01X126076D02*
G02X129900I1912J0D01*
G01Y71318D01*
G02X126076Y71319I-1912J1D01*
G01Y76319D01*
G37*
G36*
G01X633744Y962281D02*
G02X629922I-1911J0D01*
G01Y966782D01*
G02X633744Y966781I1911J-1D01*
G01Y962281D01*
G37*
G36*
G01X626750Y976831D02*
G02X622926I-1912J0D01*
G01Y981832D01*
G02X626750Y981831I1912J-1D01*
G01Y976831D01*
G37*
G36*
G01X509532Y962281D02*
G02X505708I-1912J0D01*
G01Y966782D01*
G02X509532Y966781I1912J-1D01*
G01Y962281D01*
G37*
G36*
G01X498714Y981831D02*
G02X502536I1911J0D01*
G01Y976830D01*
G02X498714Y976831I-1911J1D01*
G01Y981831D01*
G37*
G36*
G01X385320Y962281D02*
G02X381496I-1912J0D01*
G01Y966782D01*
G02X385320Y966781I1912J-1D01*
G01Y962281D01*
G37*
G36*
G01X374502Y981831D02*
G02X378324I1911J0D01*
G01Y976830D01*
G02X374502Y976831I-1911J1D01*
G01Y981831D01*
G37*
G36*
G01X250288D02*
G02X254112I1912J0D01*
G01Y976830D01*
G02X250288Y976831I-1912J1D01*
G01Y981831D01*
G37*
G36*
G01X261106Y962281D02*
G02X257284I-1911J0D01*
G01Y966782D01*
G02X261106Y966781I1911J-1D01*
G01Y962281D01*
G37*
G36*
G01X254112Y524075D02*
G02X250288I-1912J0D01*
G01Y529076D01*
G02X254112Y529075I1912J-1D01*
G01Y524075D01*
G37*
G36*
G01X136894Y962281D02*
G02X133072I-1911J0D01*
G01Y966782D01*
G02X136894Y966781I1911J-1D01*
G01Y962281D01*
G37*
G36*
G01X126076Y981831D02*
G02X129900I1912J0D01*
G01Y976830D01*
G02X126076Y976831I-1912J1D01*
G01Y981831D01*
G37*
G36*
G01X129900Y524075D02*
G02X126076I-1912J0D01*
G01Y529076D01*
G02X129900Y529075I1912J-1D01*
G01Y524075D01*
G37*
G36*
G01X1880464Y961861D02*
G02X1876642I-1911J0D01*
G01Y966362D01*
G02X1880464Y966361I1911J-1D01*
G01Y961861D01*
G37*
G36*
G01X1893126Y981831D02*
G02X1896950I1912J0D01*
G01Y976830D01*
G02X1893126Y976831I-1912J1D01*
G01Y981831D01*
G37*
G36*
G01X1756252Y961861D02*
G02X1752428I-1912J0D01*
G01Y966362D01*
G02X1756252Y966361I1912J-1D01*
G01Y961861D01*
G37*
G36*
G01X1768914Y981831D02*
G02X1772736I1911J0D01*
G01Y976830D01*
G02X1768914Y976831I-1911J1D01*
G01Y981831D01*
G37*
G36*
G01X1632000Y962381D02*
G02X1628176I-1912J0D01*
G01Y966882D01*
G02X1632000Y966881I1912J-1D01*
G01Y962381D01*
G37*
G36*
G01X1644702Y981831D02*
G02X1648524I1911J0D01*
G01Y976830D01*
G02X1644702Y976831I-1911J1D01*
G01Y981831D01*
G37*
G36*
G01X1648038Y523318D02*
G02Y519494I0J-1912D01*
G01X1643037D01*
G02X1643038Y523318I1J1912D01*
G01X1648038D01*
G37*
G36*
G01X1507786Y961821D02*
G02X1503964I-1911J0D01*
G01Y966322D01*
G02X1507786Y966321I1911J-1D01*
G01Y961821D01*
G37*
G36*
G01X1520488Y981831D02*
G02X1524312I1912J0D01*
G01Y976830D01*
G02X1520488Y976831I-1912J1D01*
G01Y981831D01*
G37*
G36*
G01X1518825Y519494D02*
G02Y523318I0J1912D01*
G01X1523826D01*
G02X1523825Y519494I-1J-1912D01*
G01X1518825D01*
G37*
G36*
G01X1383574Y961881D02*
G02X1379752I-1911J0D01*
G01Y966382D01*
G02X1383574Y966381I1911J-1D01*
G01Y961881D01*
G37*
G36*
G01X1396276Y981831D02*
G02X1400100I1912J0D01*
G01Y976830D01*
G02X1396276Y976831I-1912J1D01*
G01Y981831D01*
G37*
G36*
G01X1399613Y523318D02*
G02Y519494I0J-1912D01*
G01X1394612D01*
G02X1394613Y523318I1J1912D01*
G01X1399613D01*
G37*
G54D55*
X1130459Y883049D03*
G54D44*
X483661Y492264D03*
X607874D03*
X111024Y945020D03*
X235236D03*
X359449D03*
X483661D03*
X607874D03*
X1405906D03*
X1530118D03*
X1654331D03*
X1778543D03*
X1902756D03*
G54D42*
X111024Y188130D03*
X235236D03*
X359449D03*
X483661D03*
X607874D03*
X111024Y640886D03*
X235236D03*
X1405906D03*
X1530118D03*
X1654331D03*
G54D50*
X173228Y122047D03*
X670079D03*
G54D48*
X627263Y262981D03*
X1549901Y715737D03*
G54D53*
X1130459Y569663D03*
X1116286D03*
X1126522Y520057D03*
X1130459Y527143D03*
Y541317D03*
X1126522Y548403D03*
X1102113Y569663D03*
Y527143D03*
X1098176Y548403D03*
Y520057D03*
X1126522Y932655D03*
X1130459Y925569D03*
X1126522Y861789D03*
Y904309D03*
X1098176Y932655D03*
X1102113Y925569D03*
Y883049D03*
X1098176Y861789D03*
Y904309D03*
X1130459Y812183D03*
Y854703D03*
Y840529D03*
X1126522Y833443D03*
Y790923D03*
X1130459Y769663D03*
X1102113Y812183D03*
Y854703D03*
Y840529D03*
X1098176Y833443D03*
Y790923D03*
X1102113Y769663D03*
X1126522Y762577D03*
Y720057D03*
Y748403D03*
X1130459Y741317D03*
Y698797D03*
X1126522Y691711D03*
X1098176Y762577D03*
Y720057D03*
Y748403D03*
X1102113Y741317D03*
Y698797D03*
X1098176Y691711D03*
G54D46*
X379232Y262981D03*
X131200D03*
Y715737D03*
G54D54*
X1126522Y534230D03*
X1130459Y555490D03*
X1126522Y562576D03*
X1098176Y534230D03*
X1102113Y555490D03*
X1098176Y562576D03*
X1130459Y939742D03*
X1126522Y918482D03*
X1130459Y911396D03*
X1126522Y890136D03*
X1130459Y897222D03*
X1126522Y875962D03*
X1130459Y868876D03*
X1102113Y939742D03*
X1098176Y918482D03*
X1102113Y911396D03*
X1098176Y875962D03*
Y890136D03*
X1102113Y897222D03*
Y868876D03*
X1126522Y847616D03*
X1130459Y826356D03*
X1126522Y819270D03*
Y805096D03*
X1130459Y798010D03*
Y783836D03*
X1126522Y776750D03*
X1098176Y847616D03*
X1102113Y826356D03*
X1098176Y819270D03*
Y776750D03*
X1102113Y783836D03*
Y798010D03*
X1098176Y805096D03*
X1130459Y727144D03*
Y712970D03*
Y755490D03*
X1126522Y734230D03*
Y705884D03*
X1102113Y727144D03*
Y712970D03*
Y755490D03*
X1098176Y734230D03*
Y705884D03*
G54D52*
X1102113Y541317D03*
G54D34*
X918400Y760750D03*
G54D36*
X998600Y1300900D03*
X991500Y1312100D03*
X1020800Y1300400D03*
X991455Y1320416D03*
X996400Y1315900D03*
X996200Y1307800D03*
X1014000Y1300600D03*
X991755Y1327716D03*
X996055Y1324116D03*
X1007100Y1301100D03*
X1011100Y1305300D03*
X1019829Y1306139D03*
X1002700Y1305700D03*
X991800Y1303400D03*
X1000200Y1311700D03*
Y1320500D03*
X1016429Y1333939D03*
X1021829D03*
X1011029D03*
X1005629D03*
X986755Y1323816D03*
X986700Y1307600D03*
X1000200Y1328100D03*
X1050818Y1311189D03*
Y1316589D03*
X1045418Y1321989D03*
X1050818D03*
X1034618Y1311189D03*
X1040018D03*
X1045418D03*
X1040018Y1316589D03*
X1034618D03*
X1040018Y1321989D03*
X1031600Y1335100D03*
X1037200Y1335000D03*
X1034618Y1321989D03*
X997900Y1335800D03*
X992500D03*
X997900Y1341200D03*
X992500D03*
X997900Y1346600D03*
X992500D03*
X997900Y1352000D03*
X992500D03*
Y1357400D03*
X997900D03*
X989083Y1387764D03*
X989509Y1393422D03*
X994700Y1385000D03*
X999700Y1374500D03*
X989100Y1381700D03*
X994200Y1362700D03*
X1019829Y1389539D03*
X1013692Y1389688D03*
X1019829Y1361739D03*
X1014306Y1361710D03*
X1008870Y1361681D03*
X1003367Y1361655D03*
X1004217Y1389394D03*
X1008298Y1393071D03*
X994400Y1377300D03*
X999930Y1393070D03*
X999800Y1381600D03*
X999900Y1366800D03*
X994300Y1370100D03*
X989200Y1374800D03*
X988900Y1366900D03*
X1034600Y1349600D03*
X1042400Y1349500D03*
X1037540Y1344964D03*
X1034799Y1340183D03*
X1044700Y1335500D03*
X1043300Y1342500D03*
X1048000Y1346100D03*
X1037111Y1372380D03*
X1039988Y1367352D03*
X1044400Y1363100D03*
X1036900Y1362600D03*
X1034380Y1367469D03*
X1031300Y1362700D03*
X1042100Y1377100D03*
X1034300Y1377200D03*
X1047401Y1375084D03*
X1066481Y1327759D03*
X1061081D03*
X1066481Y1333159D03*
X1061081D03*
X1061618Y1316589D03*
X1056218Y1311189D03*
X1061618D03*
X1056218Y1316589D03*
X1060218Y1321989D03*
X1066491Y1319983D03*
X1066407Y1313972D03*
X1066481Y1338559D03*
X1061081D03*
X1066481Y1343959D03*
X1061081D03*
X1066481Y1376359D03*
Y1349359D03*
Y1354759D03*
Y1360159D03*
Y1365559D03*
Y1370959D03*
X1061081Y1376359D03*
Y1370959D03*
Y1365559D03*
Y1360159D03*
Y1354759D03*
Y1349359D03*
G54D12*
X86700Y80700D03*
X92250Y80500D03*
X92500Y62800D03*
X56750Y62000D03*
X64250Y87500D03*
X95800Y71800D03*
X30500Y67000D03*
X81500Y105000D03*
X95500Y186000D03*
X89000Y162700D03*
X73500Y120500D03*
X72900Y133000D03*
X50000Y105500D03*
X54500D03*
X59000D03*
X88000Y204000D03*
X76000Y232000D03*
X58709Y372346D03*
X84581Y397946D03*
X79581D03*
X81500Y557500D03*
X86700Y533200D03*
X92250Y533000D03*
X93800Y516800D03*
X64250Y540000D03*
X50000Y558000D03*
X54500D03*
X59000D03*
X53250Y518000D03*
X95500Y525500D03*
X76000Y642000D03*
X95500Y638500D03*
X89000Y615200D03*
X73500Y573000D03*
X72800Y585500D03*
X92000Y758000D03*
X100000Y800000D03*
X46442Y825000D03*
X88000Y946000D03*
X91114Y909791D03*
X85000Y885500D03*
X89000D03*
Y881500D03*
X85000D03*
X89000Y877500D03*
X85000D03*
X89000Y889500D03*
X85000D03*
X89000Y893500D03*
X85000D03*
X81166Y892754D03*
Y888754D03*
X83300Y908900D03*
X100310Y899557D03*
X68900Y897700D03*
X77263Y898225D03*
X83500Y898662D03*
X73430Y898509D03*
X70603Y887495D03*
X66263Y879525D03*
X67763Y883525D03*
X86700Y986200D03*
X75000Y978800D03*
X92250Y986000D03*
X95500Y968000D03*
X59000Y1011000D03*
X54500D03*
X50000D03*
X64250Y993000D03*
X53250Y971000D03*
X95500Y972500D03*
X144000Y88000D03*
X111437Y81319D03*
X106937Y84370D03*
Y93819D03*
X183500Y75450D03*
Y80250D03*
X178500Y80000D03*
X185551Y21529D03*
X151200Y48500D03*
Y44400D03*
X145864Y33216D03*
X175650Y28600D03*
X158000Y152000D03*
X154000Y106000D03*
X111437Y161319D03*
Y151319D03*
X173500Y140500D03*
X111437Y131319D03*
Y121319D03*
X127600Y119300D03*
X106937Y103268D03*
X131600Y119100D03*
X174000Y236000D03*
X118437Y199941D03*
X112000Y316000D03*
X162000Y310000D03*
X150000Y350000D03*
X189342Y378932D03*
X192842Y372000D03*
X174000Y410000D03*
X192861Y400482D03*
X181127Y471164D03*
X166727Y459964D03*
X175090Y460489D03*
X181327Y460926D03*
X171257Y460773D03*
X168430Y449759D03*
X165590Y445789D03*
X164127Y442264D03*
X156000Y544000D03*
X130000Y560000D03*
X144000Y550000D03*
X188250Y550951D03*
X106937Y556024D03*
Y537126D03*
Y546575D03*
X111437Y534075D03*
X188250Y540000D03*
X176439Y524992D03*
X182300Y558600D03*
X173600Y554400D03*
Y558600D03*
X178100D03*
X180500Y576000D03*
X162000Y614000D03*
X118437Y652697D03*
X111437Y614075D03*
Y604075D03*
Y584075D03*
Y574075D03*
X173500Y593000D03*
X140750Y575500D03*
X143000Y587000D03*
X174000Y686000D03*
X156000Y768000D03*
X150000Y800000D03*
X168937Y850845D03*
X163740Y846722D03*
X159740D03*
X154737Y854845D03*
Y850845D03*
X168937Y854845D03*
X176425Y853700D03*
X180400Y852300D03*
X176558Y831000D03*
X172318Y844782D03*
X169442Y824700D03*
X136000Y912000D03*
X140000Y938000D03*
X188000Y932000D03*
X159860Y924548D03*
X163860D03*
X168863Y916425D03*
Y920425D03*
X118437Y933209D03*
X154663Y916425D03*
Y920425D03*
X173763Y907525D03*
X189763D03*
X185763D03*
X181763D03*
X177763D03*
X193763D03*
X102263Y919025D03*
X114563Y904041D03*
X113763Y865025D03*
X106263Y900025D03*
X106363Y893425D03*
X102207Y890524D03*
X160000Y982000D03*
X111437Y956831D03*
Y986831D03*
Y971831D03*
X106937Y989882D03*
Y999331D03*
X183500Y1011000D03*
X179000D03*
X174500D03*
X188750Y993000D03*
X178200Y977700D03*
X140750Y1039250D03*
X125500Y992500D03*
X130601Y1411700D03*
X136774Y1411000D03*
X188274Y1416600D03*
X165774Y1422700D03*
X124874Y1442600D03*
X151874Y1449800D03*
X149955Y1431573D03*
X135374Y1464000D03*
Y1445500D03*
X105774Y1491000D03*
X120474Y1482800D03*
X132674Y1484200D03*
X137624Y1469000D03*
X175249Y1434075D03*
X156374Y1430500D03*
X130322Y1434014D03*
X135174Y1452400D03*
X104184Y1457200D03*
X139374Y1486100D03*
X124074Y1437200D03*
X113314Y1441700D03*
X280000Y90000D03*
X264000Y94000D03*
X231149Y93819D03*
X220000Y80500D03*
X200819Y74819D03*
X217000Y38250D03*
X198800Y34000D03*
X203078Y33972D03*
X215500Y80500D03*
X284000Y160000D03*
X256000Y142000D03*
X235649Y161319D03*
Y151319D03*
X219500Y186000D03*
X213500Y162700D03*
X235649Y131319D03*
Y121319D03*
X231149Y103268D03*
X250900Y119500D03*
X197000Y133000D03*
X197500Y120500D03*
X254900Y119600D03*
X198000Y198000D03*
X212000Y236000D03*
X288000Y242000D03*
X250000Y250000D03*
X242649Y199941D03*
X214000Y328000D03*
X250000Y350000D03*
Y300000D03*
X291042Y379232D03*
X286000Y422000D03*
X257567Y409386D03*
X261567D03*
X266764Y417509D03*
Y413509D03*
X252564D03*
Y417509D03*
X199825Y400700D03*
X204075Y398609D03*
X218214Y397600D03*
X213214D03*
X212390Y466305D03*
X198137Y461821D03*
X204090Y462289D03*
X204190Y455689D03*
X200022Y452941D03*
X212500Y557500D03*
X268000Y544000D03*
X278000Y554000D03*
X231149Y556024D03*
X232433Y537126D03*
X231149Y546575D03*
X235649Y534075D03*
X210700Y533200D03*
X216250Y533000D03*
X218000Y516600D03*
X200090Y481289D03*
X220000Y524000D03*
X286000Y612000D03*
X200000Y646000D03*
X242649Y652697D03*
X235649Y614075D03*
X213500Y615200D03*
X219500Y638500D03*
X235649Y604075D03*
Y584075D03*
Y574075D03*
X268187Y578998D03*
X197200Y585500D03*
X197500Y573000D03*
X264750Y586250D03*
X250000Y700000D03*
Y750000D03*
Y850000D03*
Y800000D03*
X291042Y831932D03*
X252000Y906000D03*
X212000Y916000D03*
X213500Y951500D03*
X263500Y939500D03*
X242649Y933209D03*
X197263Y901025D03*
X284500Y982000D03*
X252100Y959100D03*
X211200Y986200D03*
X199500Y978800D03*
X216750Y986000D03*
X231149Y989882D03*
Y999331D03*
X235649Y986831D03*
Y971831D03*
X218100Y969700D03*
X264450Y1039250D03*
X252000Y992500D03*
X220000Y978200D03*
X209374Y1416300D03*
X355362Y84370D03*
Y93819D03*
X359862Y81319D03*
X340750Y80500D03*
X335200Y80700D03*
X341800Y63700D03*
X311800Y83700D03*
X301750Y65500D03*
X340650Y69300D03*
X359862Y161319D03*
Y151319D03*
X344000Y186000D03*
X337500Y162700D03*
X298000Y140500D03*
X359862Y131319D03*
X357506Y123493D03*
X355362Y103268D03*
X375500Y119400D03*
X312750Y98500D03*
X322000Y120500D03*
X321500Y133000D03*
X293700Y105500D03*
X298500D03*
X302999Y105501D03*
X379500Y119500D03*
X324000Y196000D03*
X366862Y199941D03*
X358000Y318000D03*
X294542Y372300D03*
X320000Y422000D03*
X305775Y398909D03*
X301525Y400900D03*
X294561Y400682D03*
X320514Y397600D03*
X315514D03*
X295090Y463289D03*
X312750Y551000D03*
X335200Y533200D03*
X340750Y533000D03*
X341800Y516800D03*
X312750Y536300D03*
X299104Y556943D03*
X303604D03*
X308104D03*
X301750Y518000D03*
X344000Y525300D03*
X324000Y650000D03*
X344000Y638500D03*
X337500Y615200D03*
X322000Y573000D03*
X323380Y589452D03*
X298000Y593000D03*
X334000Y686000D03*
X342000Y758000D03*
X350000Y850000D03*
Y800000D03*
X301525Y853600D03*
X305775Y851609D03*
X294561Y853382D03*
X294542Y825000D03*
X337500Y946500D03*
X359500Y925400D03*
X358800Y955900D03*
X355362Y989882D03*
Y999331D03*
X359862Y986831D03*
Y971831D03*
X335200Y986200D03*
X323500Y978800D03*
X340750Y986000D03*
X341900Y969400D03*
X307500Y1011000D03*
X303000D03*
X298500D03*
X312750Y993000D03*
X302100Y978200D03*
X376000Y993000D03*
X344200Y978200D03*
X454000Y83800D03*
X479574Y84370D03*
Y93819D03*
X425500Y72600D03*
X435500D03*
X430500D03*
X440500D03*
X468500Y80500D03*
X465500Y38250D03*
X425500Y41250D03*
X430500D03*
X434804Y41242D03*
X444663Y32417D03*
X440400Y32400D03*
X464000Y80500D03*
X467500Y116000D03*
X394000Y164000D03*
Y174000D03*
X462000Y162700D03*
X468000Y186000D03*
X422000Y140500D03*
X479574Y103268D03*
X441300Y126000D03*
X445500Y133000D03*
X440849Y111648D03*
X437500Y134500D03*
X441500D03*
X433500D03*
X430083Y122357D03*
X388000Y196000D03*
X416000D03*
X400000Y350000D03*
X415542Y378932D03*
X419042Y372000D03*
X428000Y430000D03*
X460000Y468000D03*
X426025Y400700D03*
X419061Y400382D03*
X430275Y399351D03*
X460000Y496000D03*
X479574Y537126D03*
Y546575D03*
X459200Y533200D03*
X446993Y527868D03*
X464750Y533000D03*
X466000Y516900D03*
X436750Y538400D03*
X422500Y558000D03*
X427000D03*
X431500D03*
X429210Y512992D03*
X464801Y521156D03*
X390632Y588624D03*
X425725Y853400D03*
X429975Y851409D03*
X418761Y853082D03*
X418742Y824444D03*
X387500Y939000D03*
X462000Y947000D03*
X407000Y984000D03*
X459200Y986200D03*
X447500Y978800D03*
X464750Y986000D03*
X479574Y989882D03*
Y999331D03*
X466100Y969200D03*
X431500Y1011000D03*
X427000D03*
X422500D03*
X436750Y993000D03*
X426300Y976800D03*
X389250Y1039250D03*
X468300Y978000D03*
X532000Y90000D03*
X484074Y81319D03*
X561250Y87500D03*
X550250Y65500D03*
X556000Y156000D03*
X568000Y190000D03*
X544000Y160000D03*
X502500Y139500D03*
X512000Y104000D03*
X546500Y140500D03*
X484074Y161319D03*
Y151319D03*
X561250Y98500D03*
X570500Y120500D03*
X569900Y133000D03*
X499900Y119400D03*
X484074Y131319D03*
Y121319D03*
X547000Y105500D03*
X551500D03*
X556000D03*
X503900Y119500D03*
X534000Y222500D03*
X493000Y218500D03*
X491074Y199941D03*
X539742Y379232D03*
X543242Y372300D03*
Y400682D03*
X550225Y400900D03*
X554475Y399651D03*
X516000Y488000D03*
X574000D03*
X572000Y525800D03*
X484074Y504075D03*
X491074Y480453D03*
X483513Y535912D03*
X484074Y519075D03*
X561250Y540000D03*
X550250Y518000D03*
X516000Y637413D03*
X546500Y572000D03*
X551044Y572149D03*
X555321Y572375D03*
X517999Y583015D03*
X500000Y850000D03*
X512000Y939000D03*
X483549Y925564D03*
X532000Y983000D03*
X572000Y978800D03*
X499800Y956831D03*
X484074Y986831D03*
Y971831D03*
X556000Y1011000D03*
X551500D03*
X547000D03*
X561250Y993000D03*
X550700Y979500D03*
X513250Y1039250D03*
X500000Y992000D03*
X523455Y1416564D03*
X535200Y1466100D03*
X523500Y1455400D03*
X503001Y1454922D03*
X513624Y1458624D03*
X504000Y1470500D03*
X503035Y1444331D03*
X528250Y1470900D03*
X496500Y1476000D03*
X508867Y1497771D03*
X650000Y84000D03*
X603787Y84370D03*
Y93819D03*
X608287Y81319D03*
X589250Y80500D03*
X583700Y80700D03*
X590600Y64300D03*
X670500Y80000D03*
X589150Y69500D03*
X638000Y104000D03*
X654000Y162500D03*
X664500Y97000D03*
X579000Y105000D03*
X670500Y140500D03*
X608287Y161319D03*
Y151319D03*
X592500Y186000D03*
X586000Y162700D03*
X608287Y131319D03*
Y121319D03*
X603787Y103268D03*
X624000Y119400D03*
X626000Y140000D03*
X628000Y119500D03*
X652000Y214000D03*
X582500Y266000D03*
X615287Y199941D03*
X586500Y292000D03*
X643000Y317500D03*
X614500Y318500D03*
X639000Y354500D03*
X602500Y365000D03*
X650742Y378932D03*
X654242Y372000D03*
X661225Y400738D03*
X654261Y400382D03*
X665475Y399378D03*
X638000Y488000D03*
X603787Y537126D03*
Y546575D03*
X608287Y534075D03*
Y519075D03*
Y504075D03*
X615287Y480453D03*
X589250Y533000D03*
X583700Y533200D03*
X583550Y504600D03*
X672018Y557014D03*
X592500Y525300D03*
X666900Y665400D03*
X637750Y586250D03*
X646680Y679430D03*
X624000Y846000D03*
X666625Y853400D03*
X670875Y851409D03*
X589805Y854600D03*
X594055Y852609D03*
X659661Y853082D03*
X582667Y853605D03*
X582648Y825223D03*
X659642Y824700D03*
X585000Y948000D03*
X636000Y939000D03*
X615287Y933209D03*
X585904Y900960D03*
X589904D03*
X593904D03*
X597904D03*
X601904D03*
X652500Y984500D03*
X653500Y997500D03*
X601800Y955500D03*
X589250Y986000D03*
X603787Y989882D03*
Y999331D03*
X608287Y986831D03*
Y971831D03*
X583700Y986200D03*
X590200Y969500D03*
X671000Y1011000D03*
X624500Y993000D03*
X592800Y978100D03*
X646102Y1321750D03*
X641102D03*
X668000Y1418900D03*
X672000Y1419000D03*
X646200Y1420576D03*
X641200D03*
X637971Y1425400D03*
X657836Y1433318D03*
X658000Y1449200D03*
X665700Y1463500D03*
Y1468500D03*
X650000Y1464052D03*
Y1467948D03*
Y1457448D03*
Y1453552D03*
X636250Y1468500D03*
X628500D03*
X637972Y1441419D03*
X658000Y1444000D03*
X665700Y1458000D03*
Y1453000D03*
X624750Y1461250D03*
X712214Y82500D03*
X680500Y80250D03*
X675500Y80000D03*
X697787Y74488D03*
X714000Y38250D03*
X695600Y34000D03*
X699932Y34034D03*
X709000Y79500D03*
X711352Y26875D03*
X715205Y27012D03*
X705171Y16254D03*
X681000Y171500D03*
X716500Y186000D03*
X710300Y162700D03*
X694500Y120500D03*
X694200Y133000D03*
X753473Y138459D03*
X714000Y240000D03*
X700000Y200000D03*
X756000Y326000D03*
X718000Y332000D03*
X704500Y408500D03*
X688000Y496000D03*
X707700Y533200D03*
X696000Y525800D03*
X713250Y533000D03*
X698600Y511100D03*
X685250Y540000D03*
X680902Y557860D03*
X676402D03*
X674250Y518000D03*
X714600Y498100D03*
X716400Y525200D03*
X752200Y572300D03*
X709871Y686246D03*
X718100Y738500D03*
X718200Y744000D03*
X723000Y739200D03*
X723300Y743700D03*
X728175Y741300D03*
X728100Y745500D03*
X710000Y950500D03*
X701700Y872700D03*
X714500Y870100D03*
X723600Y872400D03*
X712760Y915137D03*
X727600Y872300D03*
X733895Y901054D03*
X754000Y884524D03*
X757600Y884400D03*
X707700Y986200D03*
X696000Y978800D03*
X713250Y986000D03*
X714400Y969600D03*
X680000Y1011000D03*
X675500D03*
X685250Y993000D03*
X675400Y980500D03*
X755200Y992400D03*
X716800Y978300D03*
X759249Y1008800D03*
X759700Y1138600D03*
X759762Y1135000D03*
X698500Y1418900D03*
X693000Y1418800D03*
X689000Y1419000D03*
X681000Y1419100D03*
X685000Y1418900D03*
X703500Y1426000D03*
X676500Y1419500D03*
X742880Y1422632D03*
X739532Y1425934D03*
X720455Y1438500D03*
X684000Y1482000D03*
X699500Y1476000D03*
X685000Y1453500D03*
X690000Y1448500D03*
X695000Y1453500D03*
X690000Y1458500D03*
Y1453500D03*
X680900Y1469200D03*
X680200Y1465500D03*
X675550Y1458721D03*
Y1452216D03*
X692000Y1471156D03*
X689250Y1433500D03*
X681250D03*
X745000Y1463000D03*
X730341Y1446725D03*
X756332Y1465934D03*
X745032Y1468534D03*
X732232Y1477094D03*
X718900Y1472800D03*
X679800Y1483500D03*
X708600Y1469900D03*
X724066Y1461018D03*
X724255Y1457253D03*
X735232Y1451210D03*
X807500Y473700D03*
X835165Y470414D03*
X787971Y466121D03*
X791971D03*
X787971Y461921D03*
X791971D03*
X787971Y457721D03*
X791971D03*
X848799Y457202D03*
X849539Y453596D03*
X827313Y464805D03*
X827361Y459317D03*
X860519Y428234D03*
X860716Y417600D03*
X850947Y417592D03*
X832417Y459017D03*
X812282Y448094D03*
X815255Y451343D03*
X808395Y454315D03*
X834000Y499000D03*
X858740Y486430D03*
X846950Y645820D03*
Y640820D03*
X822841Y662242D03*
X794883Y639984D03*
X798475Y640227D03*
X863430Y618590D03*
X788160Y666220D03*
X814320Y651120D03*
X813980Y647430D03*
X860360Y605900D03*
X836862Y637500D03*
X815148Y654937D03*
X824618Y614617D03*
X827750Y611798D03*
X791530Y614700D03*
X791680Y619050D03*
X799900Y636300D03*
X807440Y629910D03*
X802900Y634000D03*
X839400Y744920D03*
X859664Y683428D03*
X837709Y681095D03*
X789442Y681063D03*
X796200Y682400D03*
X791243Y668081D03*
X778627Y735644D03*
X778683Y745049D03*
X853900Y839200D03*
X833300Y856920D03*
X841309Y796644D03*
X841800Y804499D03*
X854973Y780437D03*
X810700Y776500D03*
X818162Y819005D03*
X810659Y767500D03*
X778735Y839888D03*
X791500Y764500D03*
X795300Y764900D03*
X826000Y857400D03*
X815469Y811029D03*
X815330Y807050D03*
X818113Y814998D03*
X834200Y796220D03*
X810700Y772000D03*
Y781000D03*
X858500Y845700D03*
X858100Y850000D03*
X848300Y847700D03*
X804200Y798200D03*
X811372Y795900D03*
X808372Y797900D03*
X805372Y801700D03*
X834470Y944430D03*
X842270Y942411D03*
X818434Y919985D03*
X820883Y879428D03*
X820900Y888500D03*
X825900Y862040D03*
X801300Y924300D03*
X799303Y927296D03*
X822463Y920345D03*
X842270Y936402D03*
X861300Y895300D03*
X819000Y896100D03*
X817337Y886075D03*
X815400Y892800D03*
X844800Y895902D03*
X845732Y891713D03*
X826000Y1004000D03*
X846500Y997500D03*
X827000Y985500D03*
X796301Y959795D03*
X822470Y981470D03*
X839970D03*
X834470D03*
X826470D03*
X848400Y974100D03*
X836953Y1023500D03*
X826000Y1062000D03*
X846500Y1055000D03*
X826000Y1094000D03*
Y1128000D03*
X844000Y1092000D03*
Y1128000D03*
X842700Y1071900D03*
X782712Y1211404D03*
Y1206904D03*
X772601Y1223511D03*
Y1219011D03*
Y1214511D03*
X777101Y1223511D03*
X832800Y1147500D03*
X795100Y1150400D03*
X798920Y1150500D03*
X821900Y1173700D03*
X773300Y1159700D03*
X769800Y1156500D03*
X776800Y1169700D03*
X780722Y1166357D03*
X780000Y1162800D03*
X859113Y1283983D03*
X822500Y1331000D03*
Y1298000D03*
Y1294000D03*
X860000Y1410843D03*
X842500Y1411343D03*
X852000Y1402000D03*
Y1406000D03*
X822500Y1373500D03*
Y1369500D03*
X835000Y1402500D03*
Y1398000D03*
X822500Y1335000D03*
X772361Y1451972D03*
X882823Y331182D03*
X909236Y333242D03*
X906486Y330524D03*
X910330Y363490D03*
X908340Y360430D03*
X909423Y354393D03*
X898059Y343029D03*
X902184Y347219D03*
X906616Y351586D03*
X922800Y362400D03*
X922700Y358100D03*
X945408Y378761D03*
X950843Y378827D03*
X871591Y431161D03*
X870400Y454315D03*
X867299Y493300D03*
Y497200D03*
X922525Y519833D03*
X873000Y494100D03*
X929096Y517567D03*
X873200Y487300D03*
X944387Y520100D03*
X941557Y547005D03*
X955000Y540800D03*
X935477Y524023D03*
X938338Y529107D03*
X938579Y551379D03*
X938623Y556600D03*
X956100Y516500D03*
X867299Y508600D03*
Y504700D03*
X935490Y519550D03*
X878740Y655190D03*
Y647190D03*
X884801Y630225D03*
X892400Y633700D03*
X878740Y643190D03*
Y651190D03*
X870200Y631500D03*
X867260Y608600D03*
X883030Y611940D03*
X878600Y615600D03*
X879600Y621600D03*
X878400Y626200D03*
X932986Y752682D03*
X874858Y757002D03*
X874706Y752583D03*
X905100Y777000D03*
X915580Y857420D03*
X942500Y797867D03*
X876255Y818998D03*
X880983Y804420D03*
X874500Y774500D03*
X936543Y762518D03*
X957500Y842400D03*
X944000D03*
X924484Y812558D03*
X921047Y811463D03*
X869989Y818847D03*
X931800Y791500D03*
X870001Y822862D03*
X934800Y795300D03*
X916855Y810934D03*
X909144Y803346D03*
X903700Y803200D03*
X912762Y792801D03*
X903221Y793938D03*
X912030Y787650D03*
X907800Y788700D03*
X913059Y810367D03*
X906166Y812784D03*
X902560Y813313D03*
X876862Y842155D03*
X881702Y838859D03*
X874593Y763800D03*
X874821Y767690D03*
X931380Y821500D03*
X935485Y821400D03*
X903572Y773740D03*
X931206Y845756D03*
X920170Y857430D03*
X903500Y769900D03*
X939500Y842400D03*
X924670Y857430D03*
X953000Y842400D03*
X911080Y857420D03*
X948500Y842400D03*
X881216Y813813D03*
X910807Y766589D03*
X904484Y786109D03*
X876256Y798895D03*
X874500Y779100D03*
X866655Y855100D03*
X870200Y852203D03*
X872600Y798700D03*
X943294Y838833D03*
X903300Y763200D03*
X879205Y873548D03*
X918369Y923258D03*
X914208Y924279D03*
X883072Y886211D03*
X889458Y907846D03*
X877877Y891277D03*
X940750Y886000D03*
X928250Y885250D03*
X934500Y885156D03*
X894317Y865406D03*
X890117D03*
X894317Y861206D03*
X890117D03*
X879667Y877303D03*
X884684Y877406D03*
X927260Y922470D03*
X909760Y925445D03*
X922760Y922470D03*
X958256Y894438D03*
X930310Y858550D03*
X879770Y868369D03*
X895500Y1038000D03*
X891600Y980000D03*
X888000D03*
X886400Y976500D03*
X893600D03*
X897200D03*
X895200Y980000D03*
X890000Y976500D03*
X944500Y1134500D03*
X952500D03*
X951500Y1117500D03*
X947000D03*
X943000D03*
X949500Y1114500D03*
X954500D03*
X956500Y1117500D03*
X948298Y1215500D03*
X943500Y1233000D03*
X951500D03*
X959500D03*
X957000Y1207500D03*
X953100Y1211400D03*
X953000Y1203600D03*
X904000Y1191700D03*
X877400D03*
X928500Y1220700D03*
X890500Y1201200D03*
X885930Y1210537D03*
X892460Y1211340D03*
X887200Y1216460D03*
X893200Y1203660D03*
X888825Y1208263D03*
X889965Y1213936D03*
X884677Y1219029D03*
X947700Y1185500D03*
X947500Y1233000D03*
X955500D03*
X926700Y1199000D03*
X952500Y1193300D03*
X884056Y1283981D03*
X871556D03*
X888000Y1424000D03*
X876500Y1410843D03*
X888776Y1402228D03*
X901435Y1402196D03*
X866500Y1392892D03*
X913935Y1402196D03*
X869937Y1400312D03*
X941559Y1408198D03*
Y1403198D03*
X945415Y1429318D03*
X945414Y1412818D03*
X1033046Y379981D03*
X1035000Y370500D03*
X1032924Y374988D03*
X1038067Y441886D03*
X1021890Y439717D03*
X965700Y519617D03*
X962118Y534117D03*
X988341Y563811D03*
X968200Y547200D03*
X985631Y559671D03*
X984197Y533383D03*
X991538Y522018D03*
X1000051Y547644D03*
X974530Y559550D03*
X974550Y563690D03*
X1003591Y552081D03*
X996998Y539555D03*
X971420Y537950D03*
X975910Y537770D03*
X990200Y544250D03*
X995213Y529837D03*
X998905Y529824D03*
X986638Y519684D03*
X991360Y529780D03*
X963870Y754152D03*
X964200Y855600D03*
X1009600Y851054D03*
X986471Y829716D03*
X1009950Y838000D03*
X1025636Y854819D03*
X962000Y842400D03*
X966861Y772518D03*
X1050774Y815327D03*
X1050650Y825420D03*
X1022838Y829101D03*
X1042545Y832026D03*
X1015950Y838000D03*
X1026932Y841614D03*
X1050082Y843729D03*
X993400Y833250D03*
X969926Y847638D03*
X971197Y775799D03*
X977676Y828513D03*
X1005272Y837091D03*
X1000827Y837072D03*
X973070Y828512D03*
X1012125Y925875D03*
X1025251Y893000D03*
X1025065Y896965D03*
X1028500Y879500D03*
X1014807Y899075D03*
X1015007Y895000D03*
X997083Y895935D03*
X986728Y891100D03*
X974120Y858920D03*
X976242Y884600D03*
X980442Y882900D03*
X993942D03*
X1027524Y948954D03*
X1039500Y891100D03*
X1037110Y859471D03*
X989100Y899600D03*
X972042Y884600D03*
X985542Y882900D03*
X989742D03*
X996938Y901170D03*
X1034200Y945000D03*
X1040200D03*
X1046272Y944928D03*
X1039500Y874700D03*
X1024129Y946152D03*
X1044800Y893750D03*
X1030862Y951946D03*
X1022080Y960728D03*
X1032361Y1114039D03*
X1021970Y1096850D03*
X960500Y1134500D03*
X982500Y1136500D03*
X986500Y1131500D03*
X1013231Y1089300D03*
X1001687Y1111499D03*
X1008739Y1096000D03*
X961000Y1117500D03*
X1029500Y1104900D03*
X1028500Y1118601D03*
X1030178Y1134165D03*
X965500Y1128000D03*
X1012800Y1122100D03*
X1002671Y1124700D03*
X1029000Y1122400D03*
X977643Y1132490D03*
X1007431Y1122900D03*
X1020000Y1230000D03*
X971700Y1193100D03*
X963500Y1233000D03*
X967500D03*
X982500Y1217000D03*
Y1209000D03*
X960900Y1211400D03*
Y1203600D03*
X982500Y1144500D03*
X1026100Y1145996D03*
X1014500Y1153500D03*
X1012000Y1150000D03*
X1017500D03*
X1020000Y1153500D03*
X982500Y1201000D03*
Y1197000D03*
Y1213000D03*
Y1221000D03*
Y1225000D03*
Y1205000D03*
X964550Y1190200D03*
X1054918Y1330439D03*
Y1325739D03*
X1024193Y1422899D03*
X1010943Y1413899D03*
X1005943Y1406700D03*
X975443Y1407700D03*
X992443Y1406700D03*
X1000443D03*
X988443D03*
X996443Y1406800D03*
X983943Y1407399D03*
X979443Y1406999D03*
X964810Y1421172D03*
X1037400Y1400600D03*
X1031400Y1399200D03*
X1054918Y1386039D03*
Y1353539D03*
Y1358239D03*
Y1381339D03*
X966985Y1393900D03*
X961857D03*
X996693Y1421399D03*
X988693D03*
X1047000Y1421800D03*
X1039900Y1417000D03*
X1002118Y1471365D03*
X998325Y1471434D03*
X992443Y1441399D03*
X1002443D03*
X997443Y1436399D03*
Y1446399D03*
Y1441399D03*
X965443Y1436399D03*
X987576Y1451454D03*
Y1455054D03*
X982343Y1446620D03*
Y1440115D03*
X961877Y1445347D03*
Y1441451D03*
X999443Y1458006D03*
X1049260Y1466691D03*
X1017618Y1470865D03*
X993830Y1471364D03*
X1017618Y1460865D03*
X1043606Y1437906D03*
X962136Y1431831D03*
X1033253Y1444649D03*
X1048553Y1448399D03*
X1035526Y1455899D03*
X1041176Y1455500D03*
X1020500Y1500014D03*
X1037550Y1475814D03*
X1098000Y378000D03*
X1136000D03*
X1100000Y350000D03*
Y300000D03*
X1150000D03*
X1144000Y418000D03*
X1136100Y460288D03*
X1147440Y473040D03*
X1143720Y468520D03*
X1143420Y472900D03*
X1139590Y468380D03*
X1139330Y472820D03*
X1135410Y468380D03*
X1135310Y472820D03*
X1130800Y472900D03*
X1131800Y446800D03*
X1136000Y446849D03*
X1092000Y448400D03*
X1088000Y448500D03*
X1103100Y457300D03*
X1095100Y455800D03*
X1113593Y476094D03*
X1093000Y502000D03*
X1149964Y481623D03*
X1102677Y487116D03*
X1119242Y477261D03*
X1083000Y620000D03*
X1095000D03*
X1112298Y618498D03*
X1134600Y618747D03*
X1118505Y658863D03*
X1114905Y658882D03*
X1129500Y619200D03*
X1138900Y584900D03*
X1125025Y621993D03*
X1056116Y697100D03*
X1057826Y680233D03*
X1059927Y688329D03*
X1064216Y683751D03*
X1067554Y694447D03*
X1071179Y682315D03*
X1112682Y681223D03*
X1107674Y677776D03*
X1141230Y673825D03*
X1103770Y675413D03*
X1075706Y941261D03*
X1141370Y905550D03*
X1058800Y893750D03*
X1130000Y994000D03*
X1106000D03*
X1138000Y970000D03*
X1093588Y972000D03*
X1110600Y964200D03*
X1108500Y960600D03*
X1104600Y967800D03*
X1101950Y962900D03*
X1101600Y953700D03*
X1087962Y959252D03*
X1084000Y1092000D03*
X1130000Y1154000D03*
X1078000Y1166000D03*
X1080000Y1230000D03*
X1068569Y1191530D03*
X1072931Y1191482D03*
X1072900Y1204500D03*
X1084571Y1200129D03*
X1072600Y1211400D03*
X1084400Y1204200D03*
X1083100Y1305600D03*
X1082080Y1299375D03*
X1126820Y1288500D03*
X1075030Y1323078D03*
X1078850Y1287900D03*
X1082080Y1309495D03*
X1123000Y1297600D03*
X1096280Y1288150D03*
X1092475Y1287971D03*
X1133480Y1296700D03*
Y1291700D03*
X1121346Y1307385D03*
Y1311385D03*
X1117000Y1332500D03*
Y1328500D03*
X1072120Y1299375D03*
Y1304495D03*
Y1309495D03*
Y1292460D03*
X1067712Y1384766D03*
X1099112Y1391273D03*
X1099100Y1375200D03*
X1099112Y1383273D03*
X1099100Y1371200D03*
X1117362Y1406073D03*
X1134112Y1363273D03*
X1122112D03*
X1091000Y1393500D03*
X1086646Y1396419D03*
X1126112Y1401773D03*
X1218000Y344000D03*
X1225600Y368700D03*
X1200000Y300000D03*
X1190000Y466000D03*
X1184000Y440000D03*
X1206000Y430500D03*
X1160900Y468500D03*
X1156110Y473330D03*
X1152600Y468470D03*
X1245567Y420602D03*
X1243500Y393600D03*
X1201000Y447000D03*
X1200500Y452000D03*
X1169000Y511500D03*
X1150900Y485100D03*
X1177100Y495300D03*
X1167000Y586500D03*
X1232490Y664290D03*
X1236690D03*
X1171700Y603700D03*
X1172500Y599700D03*
X1169125Y581776D03*
X1166550Y579200D03*
X1177350Y597792D03*
X1188000Y753500D03*
X1212587Y740895D03*
Y736695D03*
Y732495D03*
X1232490Y668490D03*
X1212587Y728295D03*
X1236690Y668490D03*
X1212587Y724095D03*
X1232490Y672690D03*
X1212587Y719895D03*
X1236690Y672690D03*
X1206414Y704261D03*
X1209931Y701608D03*
X1207468Y697962D03*
X1210283Y695565D03*
X1212587Y749295D03*
Y745095D03*
X1232490Y685290D03*
X1179129Y672187D03*
X1232490Y681090D03*
X1180000Y832000D03*
Y848000D03*
X1217089Y846182D03*
X1224088Y844900D03*
X1213611Y831932D03*
X1228344Y852351D03*
X1190995Y776395D03*
X1186690Y791440D03*
X1217111Y825000D03*
X1173990Y797760D03*
X1177300Y804960D03*
X1180520Y790880D03*
X1179690Y798020D03*
X1200337Y912300D03*
X1200407Y918060D03*
X1157556Y932754D03*
X1184778Y912848D03*
X1180090Y896524D03*
X1181550Y906100D03*
X1184750Y889200D03*
Y896300D03*
X1240000Y1070000D03*
X1176000D03*
X1200000Y1100000D03*
X1155600Y1074500D03*
X1178000Y1214000D03*
X1200000Y1200000D03*
Y1150000D03*
X1193894Y1292533D03*
X1227100D03*
X1205624D03*
X1238830D03*
X1185324Y1286563D03*
X1220450Y1292533D03*
X1216894Y1304283D03*
Y1308283D03*
X1183894Y1304783D03*
Y1308783D03*
X1188894Y1346763D03*
X1222000Y1346700D03*
X1180614Y1340033D03*
X1213820D03*
X1243768Y1376953D03*
X1208394Y1346763D03*
X1193894D03*
X1227100D03*
X1203312Y1402793D03*
X1241600Y1346763D03*
X1169412Y1396873D03*
X1326000Y92000D03*
X1297000Y68500D03*
X1319100Y47400D03*
X1308000Y35000D03*
X1261100Y16600D03*
X1264700Y16400D03*
X1314000Y150500D03*
X1302500Y152000D03*
X1256800Y132400D03*
X1322500Y113500D03*
X1317500D03*
X1327000D03*
X1262600Y119700D03*
X1262945Y377600D03*
X1294624Y358802D03*
X1316000Y419000D03*
X1269926Y400687D03*
X1262964Y400469D03*
X1274396Y407915D03*
X1247949Y423302D03*
X1250648Y425686D03*
X1245959Y435527D03*
X1265295Y421223D03*
X1257000Y434600D03*
X1248500Y393600D03*
X1277606Y546575D03*
Y556024D03*
Y537126D03*
X1282106Y519075D03*
Y534075D03*
Y504075D03*
X1325500Y504750D03*
X1323000Y566500D03*
X1318000D03*
X1328000D03*
X1300100Y530000D03*
X1326500Y514000D03*
X1312000Y501500D03*
X1272182Y571361D03*
X1332000Y646000D03*
X1282106Y614075D03*
X1273979Y652690D03*
X1282106Y574075D03*
Y604075D03*
Y584075D03*
X1272211Y575575D03*
X1254000Y748000D03*
X1278000Y810000D03*
X1250000Y820000D03*
X1337824Y832935D03*
X1247588Y842190D03*
X1270000Y868000D03*
X1274000Y933209D03*
X1325500Y907000D03*
X1266000Y1046000D03*
X1252000Y1010000D03*
X1266400Y1024700D03*
X1282106Y1036831D03*
Y1026831D03*
Y956831D03*
X1277606Y1008780D03*
Y999331D03*
Y989882D03*
X1282106Y986831D03*
Y971831D03*
X1325500Y957250D03*
X1323000Y1019000D03*
X1318000D03*
X1328000D03*
X1300900Y981800D03*
X1326500Y966500D03*
X1262400Y1024700D03*
X1312000Y954000D03*
X1260000Y993500D03*
X1266000Y1128000D03*
X1264000Y1082000D03*
X1250000Y1100000D03*
X1289106Y1105453D03*
X1282106Y1066831D03*
Y1056831D03*
X1250000Y1200000D03*
Y1150000D03*
X1273874Y1423000D03*
X1314375Y1424375D03*
X1327900Y1416500D03*
X1266914Y1394873D03*
X1258187Y1389753D03*
X1281624Y1409209D03*
X1253165Y1384633D03*
X1246949Y1379513D03*
X1263642Y1392313D03*
X1261224Y1387193D03*
X1277624Y1409209D03*
X1250347Y1382073D03*
X1289574Y1483700D03*
X1252674Y1496800D03*
X1266474Y1487500D03*
X1278574Y1488700D03*
X1282374Y1445500D03*
Y1464000D03*
X1296374Y1430700D03*
X1297089Y1450307D03*
X1322000Y1430700D03*
X1284624Y1476400D03*
X1253374Y1470000D03*
X1260574Y1445600D03*
X1256474Y1446000D03*
X1358000Y91000D03*
X1406319Y66319D03*
Y81319D03*
X1401819Y93819D03*
Y84370D03*
X1435200Y58500D03*
X1427800Y69500D03*
X1406319Y51319D03*
X1431500Y48500D03*
X1435750Y73750D03*
X1436000Y48500D03*
X1392500Y173000D03*
X1389000Y148500D03*
X1422000Y98000D03*
X1346000Y179000D03*
X1351500Y144500D03*
X1406319Y151319D03*
Y161319D03*
X1426500Y152000D03*
X1422500Y185500D03*
X1429000D03*
X1406319Y121319D03*
Y131319D03*
X1401819Y103268D03*
X1391200Y119500D03*
X1376700Y136000D03*
X1394200Y113700D03*
X1428000Y238000D03*
X1388500Y230000D03*
X1394000Y249000D03*
X1397937Y199951D03*
X1373000Y234500D03*
X1388000Y378000D03*
X1400000Y350000D03*
X1341324Y372244D03*
X1378000Y430000D03*
X1376000Y414000D03*
X1436500Y430000D03*
X1341343Y400626D03*
X1348305Y400844D03*
X1352557Y399595D03*
X1367514Y397100D03*
X1362514D03*
X1384000Y554000D03*
X1401819Y546575D03*
Y556024D03*
Y537126D03*
X1406319Y534075D03*
Y519075D03*
X1424500Y529100D03*
X1436000Y501500D03*
X1382000Y592000D03*
X1384000Y646000D03*
X1358000Y600000D03*
X1413319Y652697D03*
X1406319Y614075D03*
X1422500Y638500D03*
X1429000D03*
X1406319Y604075D03*
Y584075D03*
Y574075D03*
X1394110Y575530D03*
X1426500Y605000D03*
X1383952Y573102D03*
X1430000Y752000D03*
X1346000Y704000D03*
X1382000Y688000D03*
X1384000Y782000D03*
X1400000Y850000D03*
X1348305Y853600D03*
X1341343Y853382D03*
X1352557Y852351D03*
X1341324Y825000D03*
X1413319Y933209D03*
X1342000Y976000D03*
X1356000Y998000D03*
X1424100Y987000D03*
X1406319Y956831D03*
X1431500Y954000D03*
X1435200Y964000D03*
X1427800Y975000D03*
X1401819Y1008780D03*
Y999331D03*
Y989882D03*
X1406319Y986831D03*
Y971831D03*
X1424400Y982000D03*
X1386900Y1024600D03*
X1383200Y992700D03*
X1436000Y954000D03*
X1347400Y1416200D03*
X1474000Y78000D03*
X1482000Y66000D03*
X1530531Y66319D03*
Y81319D03*
X1526031Y93819D03*
Y84370D03*
X1439500Y81000D03*
X1530531Y51319D03*
X1450500Y61000D03*
X1508500Y102500D03*
X1441100Y130800D03*
X1494000Y98000D03*
X1484000Y158000D03*
X1530531Y151319D03*
X1526823Y161308D03*
X1437000Y185500D03*
X1438000Y150500D03*
X1530531Y121319D03*
Y131319D03*
X1526031Y103268D03*
X1515400Y119400D03*
X1501300Y136100D03*
X1447000Y113500D03*
X1442000D03*
X1452000D03*
X1511400Y119500D03*
X1523100Y193700D03*
X1502000Y196000D03*
X1457500Y289000D03*
X1508500Y292500D03*
X1450000Y350000D03*
X1462036Y379176D03*
X1465536Y372244D03*
X1484000Y432000D03*
X1476769Y399595D03*
X1465555Y400626D03*
X1472517Y400844D03*
X1492014Y397100D03*
X1487014D03*
X1480000Y546000D03*
X1526031Y546575D03*
Y556024D03*
Y537126D03*
X1530531Y534075D03*
Y519075D03*
X1449500Y504750D03*
X1447000Y566500D03*
X1442000D03*
X1452000D03*
X1450500Y514000D03*
X1451800Y583800D03*
X1498000Y586000D03*
X1490000Y598000D03*
X1500000Y640000D03*
X1460000Y646000D03*
X1530531Y614075D03*
X1437000Y638500D03*
X1530531Y604075D03*
Y584075D03*
Y574075D03*
X1515200Y572200D03*
X1438000Y603500D03*
X1511200Y572300D03*
X1508000Y748000D03*
X1472517Y853600D03*
X1465555Y853382D03*
X1462036Y831932D03*
X1476769Y852351D03*
X1465536Y825000D03*
X1443992Y904962D03*
X1442500Y984500D03*
X1478000Y976000D03*
X1530531Y956831D03*
X1526031Y1008780D03*
Y999331D03*
Y989882D03*
X1530531Y986831D03*
Y971831D03*
X1450100Y959500D03*
X1447000Y1019000D03*
X1442000D03*
X1452000D03*
X1450500Y966500D03*
X1511400Y1024600D03*
X1506000Y993000D03*
X1594000Y56000D03*
X1608000Y62000D03*
Y50000D03*
X1549300Y56000D03*
X1548500Y62900D03*
X1556700Y45000D03*
X1548279Y69309D03*
X1575400Y50750D03*
X1557500Y35000D03*
X1593500Y160500D03*
X1546000Y112000D03*
X1547000Y156222D03*
Y185500D03*
X1562500Y150500D03*
X1561500Y185500D03*
X1553500Y189500D03*
X1625300Y136000D03*
X1596400Y135600D03*
Y131100D03*
Y126100D03*
X1598000Y206000D03*
X1568000Y204000D03*
X1592000Y236000D03*
X1616100Y203786D03*
X1550000Y350000D03*
X1586249Y379176D03*
X1589749Y372244D03*
X1553500Y431500D03*
X1604000Y432500D03*
X1600982Y399595D03*
X1596730Y400844D03*
X1589768Y400626D03*
X1566500Y533000D03*
X1604000Y536000D03*
X1548600Y534900D03*
X1574000Y504750D03*
X1571500Y566500D03*
X1566500D03*
X1576500D03*
X1548400Y528800D03*
X1575000Y514000D03*
X1560500Y501500D03*
X1570100Y583800D03*
X1568000Y660000D03*
X1584000Y648000D03*
X1553500Y638500D03*
X1561500Y639860D03*
X1537500Y656000D03*
X1551000Y605000D03*
X1562500Y603500D03*
X1602000Y684000D03*
X1566000Y772000D03*
X1550000Y850000D03*
X1596730Y853600D03*
X1589768Y853382D03*
X1586249Y831932D03*
X1597000Y857500D03*
X1591400Y825000D03*
X1599000Y941000D03*
X1579000Y940000D03*
X1564000Y876000D03*
X1537531Y933209D03*
X1572900Y902900D03*
X1544000Y1004500D03*
X1566500Y985500D03*
X1600500Y975000D03*
X1612000Y980000D03*
X1548900Y987600D03*
X1556000Y954000D03*
X1559700Y964000D03*
X1552300Y975000D03*
X1574000Y957250D03*
X1571500Y1019000D03*
X1566500D03*
X1576500D03*
X1575000Y966500D03*
X1548900Y981500D03*
X1560500Y954000D03*
X1718000Y66000D03*
X1676300Y69500D03*
X1683700Y58500D03*
X1686730Y80991D03*
X1654744Y66319D03*
Y81319D03*
X1650244Y93819D03*
Y84370D03*
X1680000Y48500D03*
X1654744Y51319D03*
X1699000Y61000D03*
X1672900Y76400D03*
X1684500Y48500D03*
X1636000Y176000D03*
X1677500Y185500D03*
X1686500Y150500D03*
X1675000Y152000D03*
X1654744Y151319D03*
Y161319D03*
X1685500Y185500D03*
X1654744Y121319D03*
X1653206Y134559D03*
X1650244Y103268D03*
X1639300Y119500D03*
X1690400Y114100D03*
X1695400D03*
X1700400D03*
X1635300Y119600D03*
X1648000Y212000D03*
X1682000Y206000D03*
X1661744Y199941D03*
X1671003Y190635D03*
X1712525Y191268D03*
X1650000Y380000D03*
X1638500Y311500D03*
X1715000Y305500D03*
X1714000Y391000D03*
X1721762Y458436D03*
Y454436D03*
X1696359Y452707D03*
X1689359D03*
X1691859Y460207D03*
X1687359Y457207D03*
X1681859Y452707D03*
X1709496Y463382D03*
X1717859Y463907D03*
X1714026Y464191D03*
X1711199Y453177D03*
X1708359Y449207D03*
X1706859Y445207D03*
X1682000Y484000D03*
X1720000Y506000D03*
X1654744Y519075D03*
X1680000Y501500D03*
X1673200Y535100D03*
X1683700Y511500D03*
X1676300Y522500D03*
X1698000Y504750D03*
X1695500Y566500D03*
X1690500D03*
X1700500D03*
X1673200Y529000D03*
X1699000Y514000D03*
X1684500Y501500D03*
X1632000Y648000D03*
X1634000Y618000D03*
X1661744Y652697D03*
X1654744Y614075D03*
X1671000Y638500D03*
X1685500D03*
X1677500D03*
X1654744Y604075D03*
X1634200Y572200D03*
X1700000Y700000D03*
X1650000D03*
Y750000D03*
X1700000D03*
X1650000Y850000D03*
X1720942Y853600D03*
X1713980Y853382D03*
X1710461Y831932D03*
X1713961Y825000D03*
X1690200Y937700D03*
X1718000Y938000D03*
X1716000Y878000D03*
X1661800Y933400D03*
X1709500Y900700D03*
X1668000Y1004000D03*
X1690500Y986000D03*
X1672800Y987300D03*
X1654744Y956831D03*
X1676300Y975000D03*
X1683700Y964000D03*
X1680000Y954000D03*
X1650244Y1008780D03*
Y999331D03*
Y989882D03*
X1654744Y986831D03*
Y971831D03*
X1698000Y957250D03*
X1695500Y1019000D03*
X1690500D03*
X1700500D03*
X1699000Y966500D03*
X1672800Y981200D03*
X1635100Y1024700D03*
X1631500Y994000D03*
X1684500Y954000D03*
X1676511Y1292495D03*
X1651906Y1428973D03*
X1719726Y1402700D03*
X1716026Y1416500D03*
X1663906Y1428973D03*
X1659906D03*
X1656250Y1461250D03*
X1662626Y1464000D03*
Y1445500D03*
X1674926Y1447400D03*
X1676626Y1432000D03*
X1702501Y1434000D03*
X1661626Y1480000D03*
X1730000Y58000D03*
X1808600Y78200D03*
X1803500Y82200D03*
X1778956Y66319D03*
Y81319D03*
X1774456Y93819D03*
Y84370D03*
X1799094Y82033D03*
X1811600Y32800D03*
X1794300Y63400D03*
X1803620Y57000D03*
X1807500Y57400D03*
X1730500Y177500D03*
X1730000Y136000D03*
X1746000Y106000D03*
X1809500Y185500D03*
X1801500D03*
X1811305Y147994D03*
X1799000Y152000D03*
X1795000Y185500D03*
X1778956Y151319D03*
Y161319D03*
Y121319D03*
Y131319D03*
X1774456Y103268D03*
X1763600Y119400D03*
X1749700Y135600D03*
X1759600Y119500D03*
X1804000Y205000D03*
X1724000Y232000D03*
X1754000Y234000D03*
X1750000Y200000D03*
X1785956Y199941D03*
X1768000Y310000D03*
X1781500Y366000D03*
X1801642Y379532D03*
X1805142Y372600D03*
X1724000Y422000D03*
X1745737Y400643D03*
X1800436Y412804D03*
X1804436D03*
X1809633Y420927D03*
Y416927D03*
X1795433D03*
Y420927D03*
X1759904Y400647D03*
X1812123Y401200D03*
X1805142Y400982D03*
X1814359Y473207D03*
X1725596Y447182D03*
X1729596Y443182D03*
X1725596D03*
X1729596Y455182D03*
X1725596D03*
X1729596Y459182D03*
X1725596D03*
Y451182D03*
X1729596Y447182D03*
Y451182D03*
X1731710Y475473D03*
X1749952Y405830D03*
X1764168Y405501D03*
X1816375Y399951D03*
X1723896Y474582D03*
X1753631Y405830D03*
X1755159Y469723D03*
X1740906Y465239D03*
X1746859Y465707D03*
X1724096Y464344D03*
X1746959Y459107D03*
X1742758Y456059D03*
X1813700Y548300D03*
X1809559Y482507D03*
Y486507D03*
X1795359D03*
Y482507D03*
X1800556Y490630D03*
X1804556D03*
X1785956Y480453D03*
X1804000Y501500D03*
X1807700Y511500D03*
X1800300Y522500D03*
X1798100Y537973D03*
X1778956Y504075D03*
X1814500Y566500D03*
X1797400Y528800D03*
X1742859Y484707D03*
X1808500Y501500D03*
X1759750Y587000D03*
X1758000Y748000D03*
X1808000Y848000D03*
X1760000Y846000D03*
X1800000Y800000D03*
X1725194Y852351D03*
X1778500Y917500D03*
X1738000Y904000D03*
X1796166Y892754D03*
Y888754D03*
X1785956Y933209D03*
X1804000Y885500D03*
Y881500D03*
X1800000Y885500D03*
Y893500D03*
X1804000D03*
X1800000Y889500D03*
X1804000D03*
X1800000Y877500D03*
X1804000D03*
X1800000Y881500D03*
X1806114Y909791D03*
X1770763Y887025D03*
X1763763D03*
X1766263Y894525D03*
X1761763Y891525D03*
X1756263Y887025D03*
X1798300Y908900D03*
X1817263Y919025D03*
X1815310Y899557D03*
X1783900Y897700D03*
X1792263Y898225D03*
X1798500Y898662D03*
X1788430Y898509D03*
X1817739Y889758D03*
X1785603Y887495D03*
X1782763Y883525D03*
X1781263Y879525D03*
X1794500Y1007000D03*
X1814500Y985500D03*
X1724000Y974000D03*
X1728000Y1002000D03*
X1796900Y987200D03*
X1800300Y975000D03*
X1804000Y954000D03*
X1807700Y964000D03*
X1778956Y956831D03*
X1774456Y1008780D03*
Y999331D03*
Y989882D03*
X1778956Y986831D03*
Y971831D03*
X1814500Y1019000D03*
X1796900Y981100D03*
X1759300Y1024900D03*
X1808500Y954000D03*
X1756000Y993500D03*
X1735126Y1416300D03*
X1810426Y1476200D03*
X1790226Y1469300D03*
X1800326Y1445800D03*
X1794426Y1446400D03*
X1903169Y66319D03*
X1885200Y81000D03*
X1868600Y68922D03*
X1872900Y49000D03*
X1870607Y75897D03*
X1823300Y88600D03*
X1845900Y77300D03*
X1840900D03*
X1850800Y77200D03*
X1860500Y38100D03*
X1863950Y45400D03*
X1859050Y19000D03*
X1885508Y77413D03*
X1891300Y49400D03*
X1880500Y48900D03*
X1842400Y29500D03*
X1851500Y171500D03*
X1867600Y104300D03*
X1881000Y162200D03*
X1883000Y181500D03*
X1841000Y140000D03*
X1860817Y120141D03*
X1864800Y132500D03*
X1834018Y169783D03*
X1823500Y113500D03*
X1819134Y109132D03*
X1819000Y113500D03*
X1840500Y237500D03*
X1850000Y200000D03*
X1829500Y311000D03*
X1830000Y424000D03*
X1838000Y415500D03*
X1850000Y400000D03*
X1818359Y473207D03*
X1822359D03*
X1826359D03*
X1830359D03*
X1834359D03*
X1836476Y467034D03*
X1884000Y488000D03*
X1854000Y482000D03*
X1883200Y534600D03*
X1855750Y551000D03*
X1903169Y504075D03*
X1910169Y480453D03*
X1866700Y512800D03*
X1866500Y507250D03*
X1859300Y524500D03*
X1822000Y504750D03*
X1848500Y504000D03*
X1819500Y566500D03*
X1824500D03*
X1855750Y540000D03*
X1839750Y530250D03*
X1841500Y558000D03*
X1846000D03*
X1850500D03*
X1823000Y514000D03*
X1883300Y530000D03*
X1853000Y504000D03*
X1874540Y847322D03*
X1878540D03*
X1883737Y855445D03*
Y851445D03*
X1869537D03*
Y855445D03*
X1849407Y852351D03*
X1845155Y853600D03*
X1838193Y853382D03*
X1834674Y831932D03*
X1838174Y825000D03*
X1883663Y917025D03*
Y921025D03*
X1874660Y925148D03*
X1878660D03*
X1869463Y921025D03*
Y917025D03*
X1910169Y933209D03*
X1888763Y907525D03*
X1892763D03*
X1896763D03*
X1900763D03*
X1904763D03*
X1908763D03*
X1820700Y940600D03*
X1848500Y940200D03*
X1829563Y904041D03*
X1828763Y865025D03*
X1821263Y900025D03*
X1821363Y893425D03*
X1872500Y1010500D03*
X1903169Y956831D03*
X1859600Y960250D03*
X1883100Y984750D03*
X1870800Y973100D03*
X1898669Y1008780D03*
Y999331D03*
Y989882D03*
X1903169Y986831D03*
Y971831D03*
X1855750Y1004000D03*
X1859300Y977500D03*
X1822000Y957250D03*
X1848500Y957000D03*
X1850500Y1011000D03*
X1846000D03*
X1841500D03*
X1819500Y1019000D03*
X1824500D03*
X1855750Y993000D03*
X1823000Y966500D03*
X1839750Y983000D03*
X1875800Y981000D03*
X1853000Y957000D03*
X1827600Y970700D03*
X1824826Y1470900D03*
X1822326Y1481600D03*
X1919000Y51000D03*
X1922400Y470400D03*
X1923600Y913525D03*
X1914500Y902000D03*
X1918800Y1112100D03*
G54D33*
X862205Y277953D03*
X848032D03*
X833859D03*
X862205Y272441D03*
X848032D03*
X833859D03*
X862205Y263779D03*
X848032D03*
X833859D03*
X862205Y258268D03*
X848032D03*
X833859D03*
X855118Y282677D03*
X840945D03*
X826772D03*
X855118Y277165D03*
X840945D03*
X826772D03*
X855118Y268504D03*
X840945D03*
X826772D03*
X855118Y262992D03*
X840945D03*
X826772D03*
X862205Y306299D03*
X848032D03*
X833859D03*
X862205Y300787D03*
X848032D03*
X833859D03*
X862205Y292126D03*
X848032D03*
X833859D03*
X862205Y286614D03*
X848032D03*
X833859D03*
X855118Y311023D03*
X840945D03*
X826772D03*
X855118Y305512D03*
X840945D03*
X826772D03*
X855118Y296850D03*
X840945D03*
X826772D03*
X855118Y291338D03*
X840945D03*
X826772D03*
X904725Y272835D03*
Y277165D03*
Y282677D03*
X911811Y272441D03*
Y277953D03*
Y282283D03*
X904725Y262992D03*
Y268504D03*
X911811Y253937D03*
Y258268D03*
Y263779D03*
Y268110D03*
X897638Y282283D03*
Y272441D03*
Y277953D03*
Y253937D03*
Y268110D03*
Y258268D03*
Y263779D03*
X890552Y272835D03*
Y277165D03*
Y282677D03*
Y262992D03*
Y268504D03*
X876378Y277953D03*
Y272441D03*
Y263779D03*
Y258268D03*
X869292Y282677D03*
Y277165D03*
Y268504D03*
Y262992D03*
X904725Y305512D03*
Y311023D03*
Y315354D03*
X911811Y306299D03*
X904725Y301181D03*
X911811Y300787D03*
X904725Y287008D03*
Y291338D03*
Y296850D03*
X911811Y286614D03*
Y292126D03*
Y296457D03*
X897638Y310630D03*
Y306299D03*
Y296457D03*
Y286614D03*
Y292126D03*
Y300787D03*
X890552Y315354D03*
Y305512D03*
Y311023D03*
Y287008D03*
Y301181D03*
Y291338D03*
Y296850D03*
X876378Y306299D03*
Y300787D03*
Y292126D03*
Y286614D03*
X869292Y311023D03*
Y305512D03*
Y296850D03*
Y291338D03*
X1095420Y520057D03*
X1100932D03*
X1109593D03*
X1115105D03*
X1123766D03*
X1129278D03*
X1099357Y527143D03*
X1104869D03*
X1113530D03*
X1119042D03*
X1127703D03*
X1133215D03*
X1095420Y534230D03*
X1100932D03*
X1109593D03*
X1115105D03*
X1123766D03*
X1129278D03*
X1099357Y541317D03*
X1104869D03*
X1113530D03*
X1119042D03*
X1127703D03*
X1133215D03*
X1095420Y548403D03*
X1100932D03*
X1109593D03*
X1115105D03*
X1123766D03*
X1129278D03*
X1099357Y555490D03*
X1104869D03*
X1113530D03*
X1119042D03*
X1127703D03*
X1133215D03*
X1095420Y562576D03*
X1100932D03*
X1109593D03*
X1115105D03*
X1123766D03*
X1129278D03*
X1099357Y569663D03*
X1104869D03*
X1113530D03*
X1119042D03*
X1127703D03*
X1133215D03*
X1095420Y691711D03*
Y705884D03*
Y720057D03*
Y734230D03*
Y748403D03*
Y762577D03*
X1100932Y691711D03*
Y705884D03*
Y720057D03*
Y734230D03*
Y748403D03*
Y762577D03*
X1109593Y691711D03*
Y705884D03*
Y720057D03*
Y734230D03*
Y748403D03*
Y762577D03*
X1115105Y691711D03*
Y705884D03*
Y720057D03*
Y734230D03*
Y748403D03*
Y762577D03*
X1123766Y691711D03*
Y705884D03*
Y720057D03*
Y734230D03*
Y748403D03*
Y762577D03*
X1129278Y691711D03*
Y705884D03*
Y720057D03*
Y734230D03*
Y748403D03*
Y762577D03*
X1099357Y698797D03*
Y712970D03*
Y727144D03*
Y741317D03*
Y755490D03*
X1104869Y698797D03*
Y712970D03*
Y727144D03*
Y741317D03*
Y755490D03*
X1113530Y698797D03*
Y712970D03*
Y727144D03*
Y741317D03*
Y755490D03*
X1119042Y698797D03*
Y712970D03*
Y727144D03*
Y741317D03*
Y755490D03*
X1127703Y698797D03*
Y712970D03*
Y727144D03*
Y741317D03*
Y755490D03*
X1133215Y698797D03*
Y712970D03*
Y727144D03*
Y741317D03*
Y755490D03*
X1095420Y776750D03*
Y790923D03*
Y805096D03*
Y819270D03*
Y833443D03*
Y847616D03*
X1100932Y776750D03*
Y790923D03*
Y805096D03*
Y819270D03*
Y833443D03*
Y847616D03*
X1109593Y776750D03*
Y790923D03*
Y805096D03*
Y819270D03*
Y833443D03*
Y847616D03*
X1115105Y776750D03*
Y790923D03*
Y805096D03*
Y819270D03*
Y833443D03*
Y847616D03*
X1123766Y776750D03*
Y790923D03*
Y805096D03*
Y819270D03*
Y833443D03*
Y847616D03*
X1129278Y776750D03*
Y790923D03*
Y805096D03*
Y819270D03*
Y833443D03*
Y847616D03*
X1099357Y769663D03*
Y783836D03*
Y798010D03*
Y812183D03*
Y826356D03*
Y840529D03*
Y854703D03*
X1104869Y769663D03*
Y783836D03*
Y798010D03*
Y812183D03*
Y826356D03*
Y840529D03*
Y854703D03*
X1113530Y769663D03*
Y783836D03*
Y798010D03*
Y812183D03*
Y826356D03*
Y840529D03*
Y854703D03*
X1119042Y769663D03*
Y783836D03*
Y798010D03*
Y812183D03*
Y826356D03*
Y840529D03*
Y854703D03*
X1127703Y769663D03*
Y783836D03*
Y798010D03*
Y812183D03*
Y826356D03*
Y840529D03*
Y854703D03*
X1133215Y769663D03*
Y783836D03*
Y798010D03*
Y812183D03*
Y826356D03*
Y840529D03*
Y854703D03*
X1095420Y861789D03*
Y875962D03*
Y890136D03*
Y904309D03*
Y918482D03*
Y932655D03*
X1100932Y861789D03*
Y875962D03*
Y890136D03*
Y904309D03*
Y918482D03*
Y932655D03*
X1109593Y861789D03*
Y875962D03*
Y890136D03*
Y904309D03*
Y918482D03*
Y932655D03*
X1115105Y861789D03*
Y875962D03*
Y890136D03*
Y904309D03*
Y918482D03*
Y932655D03*
X1123766Y861789D03*
Y875962D03*
Y890136D03*
Y904309D03*
Y918482D03*
Y932655D03*
X1129278Y861789D03*
Y875962D03*
Y890136D03*
Y904309D03*
Y918482D03*
Y932655D03*
X1099357Y868876D03*
Y883049D03*
Y897222D03*
Y911396D03*
Y925569D03*
Y939742D03*
X1104869Y868876D03*
Y883049D03*
Y897222D03*
Y911396D03*
Y925569D03*
Y939742D03*
X1113530Y868876D03*
Y883049D03*
Y897222D03*
Y911396D03*
Y925569D03*
Y939742D03*
X1119042Y868876D03*
Y883049D03*
Y897222D03*
Y911396D03*
Y925569D03*
Y939742D03*
X1127703Y868876D03*
Y883049D03*
Y897222D03*
Y911396D03*
Y925569D03*
Y939742D03*
X1133215Y868876D03*
Y883049D03*
Y897222D03*
Y911396D03*
Y925569D03*
Y939742D03*
G54D15*
X26300Y873700D03*
Y864100D03*
Y868900D03*
X21500Y873700D03*
Y864100D03*
Y868900D03*
X127600Y437500D03*
Y432700D03*
X122800Y437500D03*
Y432700D03*
X127600Y427900D03*
X122800D03*
X113363Y884925D03*
X180000Y1424000D03*
Y1430000D03*
X186000Y1424000D03*
Y1430000D03*
X152000Y1377000D03*
Y1383000D03*
X158000Y1377000D03*
Y1383000D03*
X170000D03*
Y1377000D03*
X164000Y1383000D03*
Y1377000D03*
X211590Y427289D03*
X211190Y447189D03*
X513917Y1447297D03*
X507917D03*
X519717D03*
X826843Y409096D03*
Y404296D03*
Y399496D03*
X822043D03*
Y404296D03*
Y409096D03*
X807643Y408996D03*
Y404196D03*
Y399396D03*
X802843D03*
Y404196D03*
Y408996D03*
X826843Y419764D03*
Y424564D03*
Y429364D03*
X802843Y419664D03*
X807643D03*
X822043Y419764D03*
X802843Y429264D03*
Y424464D03*
X807643D03*
Y429264D03*
X822043Y429364D03*
Y424564D03*
X822400Y567100D03*
Y562300D03*
Y557500D03*
X817600D03*
Y562300D03*
Y567100D03*
X803200Y557400D03*
Y562200D03*
Y567000D03*
X798400Y557400D03*
Y562200D03*
Y567000D03*
X822400Y587368D03*
Y582568D03*
X817600D03*
Y587368D03*
X803200Y587268D03*
Y582468D03*
X798400D03*
Y587268D03*
X822400Y577768D03*
X817600D03*
X803200Y577668D03*
X798400D03*
X808300Y1197300D03*
X813100D03*
Y1206900D03*
Y1202100D03*
X808300D03*
Y1206900D03*
X794100Y1197300D03*
X789300D03*
X794100Y1202100D03*
Y1206900D03*
X789300Y1202100D03*
Y1206900D03*
X808300Y1227168D03*
Y1222368D03*
X813100D03*
Y1227168D03*
X794100D03*
Y1222368D03*
X789300D03*
Y1227168D03*
X813100Y1217568D03*
X808300D03*
X789300D03*
X794100D03*
X944200Y1083100D03*
X938900Y1103700D03*
X938800Y1109300D03*
X1012000Y371369D03*
X1015537Y365911D03*
X1038200Y762300D03*
X1021194Y766883D03*
X1035594Y766983D03*
X1040394D03*
X1021194Y771683D03*
Y776483D03*
X1035594Y776583D03*
Y771783D03*
X1040394D03*
Y776583D03*
X1016394Y766883D03*
Y776483D03*
Y771683D03*
X1119877Y408072D03*
Y403272D03*
Y398472D03*
X1124677D03*
Y403272D03*
Y408072D03*
X1100677Y407972D03*
Y403172D03*
Y398372D03*
X1105477D03*
Y403172D03*
Y407972D03*
X1119877Y423540D03*
Y428340D03*
Y418740D03*
X1124677Y428340D03*
Y423540D03*
Y418740D03*
X1105477Y428240D03*
Y423440D03*
X1100677D03*
Y428240D03*
X1105477Y418640D03*
X1100677D03*
X1057400Y771600D03*
X1057600Y776500D03*
X1067200Y786500D03*
X1062400D03*
Y781500D03*
X1057600Y786500D03*
Y781500D03*
X1067200Y791500D03*
X1062400D03*
X1067200Y796500D03*
X1062400D03*
X1057600D03*
Y791500D03*
X1128700Y1206500D03*
X1133500D03*
Y1201700D03*
X1128700D03*
X1133500Y1196900D03*
X1128700D03*
X1109600Y1197100D03*
X1114400D03*
X1109600Y1201900D03*
X1114400D03*
Y1206700D03*
X1109600D03*
X1128500Y1225700D03*
X1133300D03*
X1109400Y1221100D03*
X1114200D03*
Y1225900D03*
X1109400D03*
X1133300Y1220900D03*
X1128500D03*
X1133300Y1216100D03*
X1128500D03*
X1109400Y1216300D03*
X1114200D03*
X1117200Y1346700D03*
X1115000Y1485000D03*
X1118000Y1480500D03*
X1112000D03*
X1151100Y1179300D03*
X1155900D03*
X1151100Y1184100D03*
X1155900D03*
Y1188900D03*
X1151100D03*
X1667359Y434407D03*
Y439207D03*
Y429607D03*
X1662559D03*
Y434407D03*
Y439207D03*
X1751774Y430510D03*
X1753959Y450607D03*
X1741159Y873707D03*
X1736359D03*
X1741159Y864107D03*
X1736359D03*
X1741159Y868907D03*
X1736359D03*
X1828363Y884925D03*
G54D16*
X90709Y1485118D03*
X80709D03*
X70709D03*
X711181D03*
X701181D03*
X691181D03*
X1237953D03*
X1227953D03*
X1217953D03*
X1858425D03*
X1848425D03*
X1838425D03*
G54D22*
X111024Y188130D03*
Y640886D03*
Y1093642D03*
X235236Y188130D03*
Y640886D03*
Y1093642D03*
X359449Y188130D03*
Y640886D03*
Y1093642D03*
X483661Y188130D03*
Y640886D03*
Y1093642D03*
X607874Y188130D03*
Y640886D03*
Y1093642D03*
X732087Y188130D03*
Y640886D03*
Y1093642D03*
X1281693Y188130D03*
Y640886D03*
Y1093642D03*
X1405906Y188130D03*
Y640886D03*
Y1093642D03*
X1530118Y188130D03*
Y640886D03*
Y1093642D03*
X1654331Y188130D03*
Y640886D03*
Y1093642D03*
X1778543Y188130D03*
Y640886D03*
Y1093642D03*
X1902756Y188130D03*
Y640886D03*
Y1093642D03*
G54D17*
X127988Y67319D03*
Y71319D03*
Y76319D03*
Y80319D03*
X134983Y61269D03*
Y56769D03*
X127988Y520075D03*
Y524075D03*
Y529075D03*
Y533075D03*
X134983Y514025D03*
Y509525D03*
X127988Y972831D03*
Y976831D03*
Y981831D03*
Y985831D03*
X134983Y970781D03*
Y966781D03*
Y962281D03*
Y958281D03*
X252200Y67319D03*
Y71319D03*
Y76319D03*
Y80319D03*
X259195Y61269D03*
Y56769D03*
X252200Y520075D03*
Y524075D03*
Y529075D03*
Y533075D03*
X259195Y514025D03*
Y509525D03*
X252200Y972831D03*
Y976831D03*
Y981831D03*
Y985831D03*
X259195Y970781D03*
Y966781D03*
Y962281D03*
Y958281D03*
X376413Y67319D03*
Y71319D03*
Y76319D03*
Y80319D03*
X383408Y61269D03*
Y56769D03*
X376413Y524075D03*
Y529075D03*
X383408Y514025D03*
Y509525D03*
X376413Y972831D03*
Y976831D03*
Y981831D03*
Y985831D03*
X383408Y970781D03*
Y966781D03*
Y962281D03*
Y958281D03*
X500625Y67319D03*
Y71319D03*
Y76319D03*
Y80319D03*
X507620Y61269D03*
Y56769D03*
X500625Y524075D03*
Y529075D03*
X507620Y518025D03*
Y514025D03*
Y509525D03*
Y505525D03*
X500625Y972831D03*
Y976831D03*
Y981831D03*
Y985831D03*
X507620Y970781D03*
Y966781D03*
Y962281D03*
Y958281D03*
X624838Y67319D03*
Y71319D03*
Y76319D03*
Y80319D03*
X631833Y61269D03*
Y56769D03*
X624838Y524075D03*
Y529075D03*
X631833Y518025D03*
Y514025D03*
Y509525D03*
Y505525D03*
X624838Y972831D03*
Y976831D03*
Y981831D03*
Y985831D03*
X631833Y970781D03*
Y966781D03*
Y962281D03*
Y958281D03*
X749051Y71319D03*
Y76319D03*
X756046Y61269D03*
Y56769D03*
X749051Y524075D03*
Y529075D03*
X756046Y514025D03*
Y509525D03*
X749051Y976831D03*
Y981831D03*
X756046Y966781D03*
Y962281D03*
X1275400Y68650D03*
X1270400D03*
X1256750Y53650D03*
X1261250D03*
X1279400Y521406D03*
X1275400D03*
X1270400D03*
X1266400D03*
X1252750Y506406D03*
X1256750D03*
X1261250D03*
X1265250D03*
X1273975Y972831D03*
Y976831D03*
Y981831D03*
Y985831D03*
X1257490Y970361D03*
Y966361D03*
Y961861D03*
Y957861D03*
X1403613Y68650D03*
X1399613D03*
X1394613D03*
X1390613D03*
X1376963Y53650D03*
X1380963D03*
X1385463D03*
X1389463D03*
X1403613Y521406D03*
X1399613D03*
X1394613D03*
X1390613D03*
X1380963Y506406D03*
X1385463D03*
X1398188Y972831D03*
Y976831D03*
Y981831D03*
Y985831D03*
X1381663Y970381D03*
Y966381D03*
Y961881D03*
Y957881D03*
X1527825Y68650D03*
X1523825D03*
X1518825D03*
X1514825D03*
X1501175Y53650D03*
X1505175D03*
X1509675D03*
X1513675D03*
X1527825Y521406D03*
X1523825D03*
X1518825D03*
X1514825D03*
X1505175Y506406D03*
X1509675D03*
X1522400Y972831D03*
Y976831D03*
Y981831D03*
Y985831D03*
X1505875Y970321D03*
Y966321D03*
Y961821D03*
Y957821D03*
X1625388Y53650D03*
X1652038Y68650D03*
X1648038D03*
X1643038D03*
X1639038D03*
X1629388Y53650D03*
X1633888D03*
X1637888D03*
X1652038Y521406D03*
X1648038D03*
X1643038D03*
X1639038D03*
X1629388Y506406D03*
X1633888D03*
X1646613Y972831D03*
Y976831D03*
Y981831D03*
Y985831D03*
X1630088Y970881D03*
Y966881D03*
Y962381D03*
Y958381D03*
X1776250Y68650D03*
X1772250D03*
X1767250D03*
X1763250D03*
X1753600Y53650D03*
X1758100D03*
X1772250Y521406D03*
X1767250D03*
X1749600Y506406D03*
X1753600D03*
X1758100D03*
X1762100D03*
X1770825Y972831D03*
Y976831D03*
Y981831D03*
Y985831D03*
X1754340Y970361D03*
Y966361D03*
Y961861D03*
Y957861D03*
X1900463Y68650D03*
X1896463D03*
X1891463D03*
X1887463D03*
X1877813Y53650D03*
X1882313D03*
X1896463Y521406D03*
X1891463D03*
X1873813Y506406D03*
X1877813D03*
X1882313D03*
X1886313D03*
X1895038Y972831D03*
Y976831D03*
Y981831D03*
Y985831D03*
X1878553Y970361D03*
Y966361D03*
Y961861D03*
Y957861D03*
G54D19*
X111024Y39508D03*
Y492264D03*
Y945020D03*
X235236Y39508D03*
Y492264D03*
Y945020D03*
X359449Y39508D03*
Y492264D03*
Y945020D03*
X483661Y39508D03*
Y492264D03*
Y945020D03*
X607874Y39508D03*
Y492264D03*
Y945020D03*
X732087Y39508D03*
Y492264D03*
Y945020D03*
X1281693Y39508D03*
Y492264D03*
Y945020D03*
X1405906Y39508D03*
Y492264D03*
Y945020D03*
X1530118Y39508D03*
Y492264D03*
Y945020D03*
X1654331Y39508D03*
Y492264D03*
Y945020D03*
X1778543Y39508D03*
Y492264D03*
Y945020D03*
X1902756Y39508D03*
Y492264D03*
Y945020D03*
G54D35*
X974015Y261812D03*
X986614D03*
X974015Y267717D03*
Y255906D03*
X986614Y267717D03*
Y255906D03*
X1002362Y307087D03*
X1014960D03*
X1030709D03*
X1043307D03*
X1002362Y312993D03*
X1030709D03*
X1002362Y301182D03*
X1030709D03*
X1014960Y312993D03*
X1043307D03*
X1014960Y301182D03*
X1043307D03*
X1101405Y1120040D03*
X1119633D03*
X1101405Y1132638D03*
X1119633D03*
X1108098Y1120040D03*
X1126326D03*
X1108098Y1132638D03*
X1126326D03*
G54D18*
X134983Y65269D03*
Y52769D03*
Y518025D03*
Y505525D03*
X259195Y65269D03*
Y52769D03*
X203300Y71700D03*
X215100Y62940D03*
X207000Y80500D03*
X259195Y518025D03*
Y505525D03*
X383408Y65269D03*
Y52769D03*
Y518025D03*
Y505525D03*
X380780Y1428599D03*
Y1422599D03*
Y1416599D03*
Y1410599D03*
X374780Y1428599D03*
Y1422599D03*
Y1416599D03*
Y1410599D03*
X380780Y1434599D03*
X374780D03*
X462100Y62940D03*
X450300Y71700D03*
X507620Y65269D03*
Y52769D03*
X542066Y1440238D03*
X537466D03*
X532866D03*
X528798Y1437733D03*
X524722Y1436362D03*
X631833Y65269D03*
Y52769D03*
X756046Y65269D03*
Y52769D03*
X704000Y80500D03*
X700300Y71700D03*
X712000Y62940D03*
X756046Y518025D03*
Y505525D03*
Y970781D03*
Y958281D03*
X786200Y1334100D03*
X794200D03*
X801000Y1333800D03*
X786200Y1326100D03*
X794200D03*
X801000Y1325800D03*
X944019Y1452220D03*
X1121346Y1315676D03*
Y1319676D03*
X1105100Y1351000D03*
Y1355000D03*
X1099112Y1387273D03*
Y1379273D03*
X1216894Y1318783D03*
Y1314783D03*
X1183894Y1319783D03*
Y1315783D03*
X1236600Y1346763D03*
X1232100D03*
X1217100D03*
X1183894D03*
X1203394D03*
X1198894D03*
X1334500Y549500D03*
Y554500D03*
Y539500D03*
Y544500D03*
Y1002000D03*
Y1007000D03*
Y992000D03*
Y997000D03*
X1458500Y86500D03*
Y91500D03*
Y96500D03*
Y101500D03*
Y544500D03*
Y539500D03*
Y554500D03*
Y549500D03*
Y1002000D03*
Y1007000D03*
Y992000D03*
Y997000D03*
X1583000Y544500D03*
Y539500D03*
Y554500D03*
Y549500D03*
Y997000D03*
Y992000D03*
Y1007000D03*
Y1002000D03*
X1692200Y86200D03*
Y91200D03*
X1692300Y96100D03*
X1707000Y103500D03*
X1707083Y543435D03*
Y538435D03*
X1706800Y556300D03*
X1706935Y548158D03*
X1707000Y997000D03*
Y992000D03*
Y1007000D03*
Y1002000D03*
X1884600Y49000D03*
X1831000Y544500D03*
Y539500D03*
Y554500D03*
Y549500D03*
Y1002000D03*
Y1007000D03*
Y992000D03*
Y997000D03*
G54D11*
X78000Y44000D03*
X38000Y86000D03*
X100412Y6000D03*
X95412D03*
X90412D03*
X85412D03*
X80412D03*
X75412D03*
X70412D03*
X65412D03*
X60412D03*
X55412D03*
X50412D03*
X45412D03*
X40412D03*
X35412D03*
X30412D03*
X25412D03*
X20412D03*
X15412D03*
X10412D03*
X6000Y6588D03*
Y11588D03*
Y16588D03*
Y21588D03*
Y26588D03*
Y31588D03*
Y36588D03*
Y41588D03*
Y46588D03*
Y51588D03*
Y56588D03*
Y61588D03*
Y66588D03*
Y71588D03*
Y76588D03*
Y81588D03*
Y86588D03*
Y91588D03*
X75000Y73300D03*
X74000Y87500D03*
X89000D03*
X84000D03*
X79000D03*
X48000Y160000D03*
X6000Y96588D03*
Y101588D03*
Y106588D03*
Y111588D03*
Y116588D03*
Y121588D03*
Y126588D03*
Y131588D03*
Y136588D03*
Y141588D03*
Y146588D03*
Y151588D03*
Y156588D03*
Y161588D03*
Y166588D03*
Y171588D03*
Y176588D03*
Y181588D03*
Y186588D03*
X49500Y140500D03*
X64250Y98500D03*
X50000Y200000D03*
X6000Y191588D03*
Y196588D03*
Y201588D03*
Y206588D03*
Y211588D03*
Y216588D03*
Y221588D03*
Y226588D03*
Y231588D03*
Y236588D03*
Y241588D03*
Y246588D03*
Y251588D03*
Y256588D03*
Y261588D03*
Y266588D03*
Y271588D03*
Y276588D03*
Y281588D03*
X38000Y348000D03*
X6000Y286588D03*
Y291588D03*
Y296588D03*
Y301588D03*
Y306588D03*
Y311588D03*
Y316588D03*
Y321588D03*
Y326588D03*
Y331588D03*
Y336588D03*
Y341588D03*
Y346588D03*
Y351588D03*
Y356588D03*
Y361588D03*
Y366588D03*
Y371588D03*
Y376588D03*
X55209Y379278D03*
X38000Y418000D03*
Y452000D03*
X6000Y441588D03*
Y436588D03*
Y431588D03*
Y426588D03*
Y421588D03*
Y416588D03*
Y411588D03*
Y406588D03*
Y386588D03*
Y391588D03*
Y396588D03*
Y401588D03*
Y446588D03*
Y451588D03*
Y456588D03*
Y461588D03*
Y381588D03*
Y466588D03*
Y471588D03*
X65692Y392187D03*
X58728Y393206D03*
X88000Y498000D03*
Y478000D03*
X38000Y544000D03*
X6000Y476588D03*
Y481588D03*
Y486588D03*
Y491588D03*
Y496588D03*
Y501588D03*
Y506588D03*
Y511588D03*
Y516588D03*
Y521588D03*
Y526588D03*
Y531588D03*
Y536588D03*
Y541588D03*
Y546588D03*
Y551588D03*
Y556588D03*
Y561588D03*
Y566588D03*
Y571588D03*
X64250Y551000D03*
X75000Y525800D03*
X79000Y540000D03*
X84000D03*
X89000D03*
X74000D03*
X40000Y614000D03*
X38000Y660000D03*
X6000Y576588D03*
Y581588D03*
Y586588D03*
Y591588D03*
Y596588D03*
Y601588D03*
Y606588D03*
Y611588D03*
Y616588D03*
Y621588D03*
Y626588D03*
Y631588D03*
Y636588D03*
Y641588D03*
Y646588D03*
Y651588D03*
Y656588D03*
Y661588D03*
Y666588D03*
X49500Y593000D03*
X6000Y671588D03*
Y676588D03*
Y681588D03*
Y686588D03*
Y691588D03*
Y696588D03*
Y701588D03*
Y706588D03*
Y711588D03*
Y716588D03*
Y721588D03*
Y726588D03*
Y731588D03*
Y736588D03*
Y741588D03*
Y746588D03*
Y751588D03*
Y756588D03*
Y761588D03*
X34000Y792000D03*
X6000Y766588D03*
Y771588D03*
Y776588D03*
Y781588D03*
Y786588D03*
Y791588D03*
Y796588D03*
Y801588D03*
Y806588D03*
Y811588D03*
Y816588D03*
Y821588D03*
Y826588D03*
Y831588D03*
Y836588D03*
Y841588D03*
Y846588D03*
Y851588D03*
Y856588D03*
X53425Y853600D03*
X46461Y853382D03*
X42942Y831932D03*
X73526Y850100D03*
X68526D03*
X26000Y908000D03*
Y940000D03*
X6000Y861588D03*
Y866588D03*
Y871588D03*
Y876588D03*
Y881588D03*
Y886588D03*
Y891588D03*
Y896588D03*
Y901588D03*
Y906588D03*
Y911588D03*
Y916588D03*
Y921588D03*
Y926588D03*
Y931588D03*
Y936588D03*
Y941588D03*
Y946588D03*
Y951588D03*
X81500Y1010500D03*
X38000Y996000D03*
X6000Y956588D03*
Y961588D03*
Y966588D03*
Y971588D03*
Y976588D03*
Y981588D03*
Y986588D03*
Y991588D03*
Y996588D03*
Y1001588D03*
Y1006588D03*
Y1011588D03*
Y1016588D03*
Y1021588D03*
Y1026588D03*
Y1031588D03*
Y1036588D03*
Y1041588D03*
Y1046588D03*
X73500Y1026000D03*
X72600Y1038400D03*
X49500Y1046000D03*
X64250Y1004000D03*
X74000Y993000D03*
X89000D03*
X84000D03*
X79000D03*
X50000Y1100000D03*
X6000Y1051588D03*
Y1056588D03*
Y1061588D03*
Y1066588D03*
Y1071588D03*
Y1076588D03*
Y1081588D03*
Y1086588D03*
Y1091588D03*
Y1096588D03*
Y1101588D03*
Y1106588D03*
Y1111588D03*
Y1116588D03*
Y1121588D03*
Y1126588D03*
Y1131588D03*
Y1136588D03*
Y1141588D03*
X95500Y1091500D03*
X89000Y1068200D03*
X50000Y1150000D03*
Y1200000D03*
X6000Y1146588D03*
Y1151588D03*
Y1156588D03*
Y1161588D03*
Y1166588D03*
Y1171588D03*
Y1176588D03*
Y1181588D03*
Y1186588D03*
Y1191588D03*
Y1196588D03*
Y1201588D03*
Y1206588D03*
Y1211588D03*
Y1216588D03*
Y1221588D03*
Y1226588D03*
Y1231588D03*
Y1236588D03*
X100000Y1250000D03*
X50000D03*
Y1300000D03*
X100000D03*
X6000Y1321588D03*
Y1326588D03*
Y1331588D03*
Y1286588D03*
Y1291588D03*
Y1296588D03*
Y1301588D03*
Y1306588D03*
Y1311588D03*
Y1316588D03*
Y1241588D03*
Y1246588D03*
Y1251588D03*
Y1256588D03*
Y1261588D03*
Y1266588D03*
Y1271588D03*
Y1276588D03*
Y1281588D03*
X50000Y1350000D03*
X100000D03*
Y1400000D03*
X50000D03*
X6000Y1421588D03*
Y1416588D03*
Y1411588D03*
Y1406588D03*
Y1401588D03*
Y1396588D03*
Y1391588D03*
Y1386588D03*
Y1381588D03*
Y1376588D03*
Y1371588D03*
Y1366588D03*
Y1361588D03*
Y1356588D03*
Y1351588D03*
Y1346588D03*
Y1341588D03*
Y1426588D03*
Y1336588D03*
X86000Y1444000D03*
X6000Y1451588D03*
Y1446588D03*
Y1441588D03*
Y1436588D03*
Y1431588D03*
X99000Y1501000D03*
X61500Y1502000D03*
X87539Y1499118D03*
X82539D03*
X77539D03*
X72539D03*
X67539D03*
X92539D03*
X11000Y1455500D03*
X15500Y1458500D03*
X17811Y1462693D03*
Y1467693D03*
Y1472693D03*
Y1477693D03*
Y1482693D03*
Y1487693D03*
Y1492693D03*
Y1497693D03*
Y1502693D03*
Y1507693D03*
X17500Y1512000D03*
X21819Y1513685D03*
X26819D03*
X31819D03*
X36819D03*
X41819D03*
X46819D03*
X51819D03*
X56819D03*
X58500Y1508000D03*
X195412Y6000D03*
X190412D03*
X185412D03*
X180412D03*
X175412D03*
X170412D03*
X165412D03*
X160412D03*
X155412D03*
X150412D03*
X145412D03*
X140412D03*
X135412D03*
X130412D03*
X125412D03*
X120412D03*
X115412D03*
X110412D03*
X105412D03*
X111437Y66319D03*
Y51319D03*
X118437Y27697D03*
X157900Y17900D03*
X157600Y24500D03*
X157400Y35800D03*
X102000Y440000D03*
X152000Y492000D03*
X160000Y508000D03*
X111437Y519075D03*
Y504075D03*
X118437Y480453D03*
X176506Y539295D03*
X191026Y850100D03*
X196026D03*
X180500Y1028500D03*
X142000Y1008000D03*
X140750Y1028500D03*
X174000Y1046000D03*
X111437Y1036831D03*
Y1026831D03*
X188750Y1004000D03*
X106937Y1008780D03*
X136500Y1111500D03*
X164000Y1068000D03*
X118437Y1105453D03*
X111437Y1066831D03*
Y1056831D03*
X158484Y1416000D03*
X139774Y1420600D03*
X131143Y1427661D03*
X102000Y1505500D03*
X177433Y1513685D03*
X182433D03*
X187433D03*
X192433D03*
X147433D03*
X152433D03*
X157433D03*
X162433D03*
X167433D03*
X172433D03*
X103000Y1511000D03*
X107433Y1513685D03*
X112433D03*
X117433D03*
X122433D03*
X127433D03*
X132433D03*
X137433D03*
X157574Y1453500D03*
X145374Y1452500D03*
X145274Y1434685D03*
X156674Y1435085D03*
X167499Y1434000D03*
X104074Y1462500D03*
X114874Y1476700D03*
X118574Y1465900D03*
X121274Y1447400D03*
X142433Y1513685D03*
X262000Y30000D03*
X290412Y6000D03*
X285412D03*
X280412D03*
X275412D03*
X270412D03*
X265412D03*
X260412D03*
X255412D03*
X250412D03*
X245412D03*
X240412D03*
X235412D03*
X230412D03*
X225412D03*
X220412D03*
X215412D03*
X210412D03*
X205412D03*
X200412D03*
X231000Y82000D03*
X235649Y81319D03*
Y66319D03*
Y51319D03*
X242649Y27697D03*
X203000Y87500D03*
X213000D03*
X208000D03*
X197500D03*
X271590Y469789D03*
X275590D03*
X279590D03*
X283590D03*
X287590D03*
X291590D03*
X216000Y498000D03*
X286000Y490000D03*
Y506000D03*
X235649Y519075D03*
Y504075D03*
X242649Y480453D03*
X199000Y525800D03*
X203000Y540000D03*
X208000D03*
X213000D03*
X198000D03*
X265000Y1008500D03*
X206000Y1010500D03*
X198000Y1026000D03*
X197300Y1038500D03*
X264250Y1028500D03*
X235649Y1036831D03*
Y1026831D03*
X231149Y1008780D03*
X198500Y993000D03*
X213500D03*
X208500D03*
X203500D03*
X288000Y1068000D03*
X200000Y1100000D03*
X242649Y1105453D03*
X220000Y1091500D03*
X213500Y1068200D03*
X235649Y1066831D03*
Y1056831D03*
X200000Y1200000D03*
X250000D03*
Y1150000D03*
X200000D03*
X227500Y1303000D03*
X250000Y1350000D03*
X233074Y1429500D03*
X239274Y1429600D03*
X237235Y1419039D03*
X236974Y1425000D03*
X259500Y1494000D03*
X256000Y1466000D03*
X283000Y1492000D03*
X279000Y1498500D03*
X197433Y1513685D03*
X202433D03*
X207433D03*
X212433D03*
X217433D03*
X222433D03*
X227433D03*
X232433D03*
X237433D03*
X242433D03*
X247433D03*
X252433D03*
X257433D03*
X262433D03*
X267433D03*
X272433D03*
X277433D03*
X278646Y1509398D03*
Y1504398D03*
X288685Y1490063D03*
X386000Y28000D03*
X338000Y30000D03*
Y44000D03*
X385412Y6000D03*
X380412D03*
X375412D03*
X370412D03*
X365412D03*
X360412D03*
X355412D03*
X350412D03*
X345412D03*
X340412D03*
X335412D03*
X330412D03*
X325412D03*
X320412D03*
X315412D03*
X310412D03*
X305412D03*
X300412D03*
X295412D03*
X359862Y66319D03*
X323500Y73300D03*
X359862Y51319D03*
X366862Y27697D03*
X327500Y87500D03*
X332500D03*
X337500D03*
X322500D03*
X336000Y466000D03*
X384000Y468000D03*
X338000Y498000D03*
X355362Y556024D03*
Y537126D03*
Y546575D03*
X359862Y534075D03*
Y519075D03*
Y504075D03*
X366862Y480453D03*
X323500Y525800D03*
X322500Y540000D03*
X337500D03*
X332500D03*
X327500D03*
X359862Y614075D03*
X366862Y652697D03*
X359862Y604075D03*
Y584075D03*
X374261Y572963D03*
X320526Y850100D03*
X315526D03*
X330000Y1010500D03*
X304500Y1028500D03*
X359862Y1036831D03*
Y1026831D03*
X322000Y1026000D03*
X321200Y1038500D03*
X298000Y1046000D03*
X355362Y1008780D03*
X312750Y1004000D03*
X322500Y993000D03*
X337500D03*
X332500D03*
X327500D03*
X318000Y1058000D03*
X326000Y1106000D03*
X366862Y1105453D03*
X359862Y1066831D03*
Y1056831D03*
X344000Y1091500D03*
X337500Y1068200D03*
X300000Y1200000D03*
Y1150000D03*
X384055Y1330472D03*
Y1320472D03*
X354055Y1330472D03*
X364055D03*
X354055Y1320472D03*
X364055D03*
X324055Y1330472D03*
X334055D03*
X324055Y1320472D03*
X334055D03*
X304055Y1330472D03*
Y1320472D03*
X294055Y1330472D03*
Y1320472D03*
X384055Y1340472D03*
Y1350472D03*
X354055Y1340472D03*
Y1350472D03*
X364055Y1340472D03*
Y1350472D03*
X324055Y1340472D03*
Y1350472D03*
X334055Y1340472D03*
Y1350472D03*
X304055D03*
Y1340472D03*
X294055Y1350472D03*
Y1340472D03*
X350000Y1400000D03*
X323688Y1357736D03*
X328688D03*
X333688D03*
X338688D03*
X343688D03*
X348688D03*
X353688D03*
X358688D03*
X363688D03*
X368688D03*
X373688D03*
X378688D03*
X383688D03*
X298688D03*
X303688D03*
X308688D03*
X313688D03*
X318688D03*
X293688D03*
X300000Y1400000D03*
X293685Y1490063D03*
X298685D03*
X303685D03*
X308685D03*
X313685D03*
X318685D03*
X323685D03*
X328685D03*
X333685D03*
X338685D03*
X343685D03*
X348685D03*
X353685D03*
X358685D03*
X363685D03*
X368685D03*
X373685D03*
X378685D03*
X383685D03*
X410679Y31098D03*
X414000Y58000D03*
X402000Y64000D03*
X480412Y6000D03*
X475412D03*
X470412D03*
X465412D03*
X460412D03*
X455412D03*
X450412D03*
X445412D03*
X440412D03*
X435412D03*
X430412D03*
X425412D03*
X420412D03*
X415412D03*
X410412D03*
X405412D03*
X400412D03*
X395412D03*
X390412D03*
X446400Y91100D03*
X456900D03*
X461900D03*
X451900D03*
X445014Y397600D03*
X440014D03*
X402000Y560000D03*
X388000Y548000D03*
X410000Y544000D03*
X392000Y490000D03*
X479574Y556024D03*
X436750Y551000D03*
X446500Y540000D03*
X461500D03*
X456500D03*
X451500D03*
X410000Y616000D03*
X468000Y638500D03*
X467029Y610775D03*
X441641Y574141D03*
X445546Y586021D03*
X421820Y593641D03*
X389250Y575500D03*
X422000Y684000D03*
X454000Y686000D03*
X466000Y762000D03*
X400000Y800000D03*
X415242Y831882D03*
X440026Y850100D03*
X445026D03*
X428500Y1028500D03*
X454000Y1010500D03*
X389500Y1009000D03*
X446000Y1026000D03*
X445100Y1038500D03*
X389250Y1028500D03*
X422000Y1046000D03*
X436750Y1004000D03*
X479574Y1008780D03*
X446500Y993000D03*
X461500D03*
X456500D03*
X451500D03*
X448000Y1106000D03*
X410000Y1068000D03*
X468000Y1091500D03*
X462000Y1068200D03*
X450000Y1150000D03*
Y1200000D03*
X474055Y1330472D03*
X484055D03*
X474055Y1320472D03*
X484055D03*
X444055Y1330472D03*
X454055D03*
X444055Y1320472D03*
X454055D03*
X414055Y1330472D03*
X424055D03*
X414055Y1320472D03*
X424055D03*
X394055Y1330472D03*
Y1320472D03*
X474055Y1340472D03*
Y1350472D03*
X484055Y1340472D03*
Y1350472D03*
X444055Y1340472D03*
Y1350472D03*
X454055Y1340472D03*
Y1350472D03*
X414055Y1340472D03*
Y1350472D03*
X424055Y1340472D03*
Y1350472D03*
X394055Y1340472D03*
Y1350472D03*
X390500Y1386000D03*
X388688Y1357736D03*
X393688D03*
X462000Y1382985D03*
Y1372985D03*
Y1362985D03*
X474000Y1382985D03*
Y1372985D03*
Y1362985D03*
X426000D03*
X450000Y1372985D03*
Y1382985D03*
X414000Y1372985D03*
X450000Y1362985D03*
X438000Y1372985D03*
X414000Y1362985D03*
X438000D03*
X426000Y1372985D03*
X438000Y1382985D03*
X414000D03*
X426000D03*
X388685Y1490063D03*
X393685D03*
X398685D03*
X403685D03*
X408685D03*
X413685D03*
X418685D03*
X423685D03*
X428685D03*
X433685D03*
X438685D03*
X443685D03*
X448685D03*
X453685D03*
X458685D03*
X463685D03*
X468685D03*
X473685D03*
X478685D03*
X534000Y58000D03*
X512000Y28000D03*
X575412Y6000D03*
X570412D03*
X565412D03*
X560412D03*
X555412D03*
X550412D03*
X545412D03*
X540412D03*
X535412D03*
X530412D03*
X525412D03*
X520412D03*
X515412D03*
X510412D03*
X505412D03*
X500412D03*
X495412D03*
X490412D03*
X485412D03*
X572000Y73300D03*
X484074Y66319D03*
Y51319D03*
X491074Y27697D03*
X576000Y87500D03*
X571000D03*
X569014Y397600D03*
X564014D03*
X524000Y560000D03*
X561250Y551000D03*
X571000Y540000D03*
X576000D03*
X536000Y644000D03*
X510000Y656000D03*
X491074Y652697D03*
X484074Y614075D03*
X565279Y578552D03*
X569900Y585500D03*
X551276Y597925D03*
X483265Y606243D03*
X484074Y584075D03*
Y574075D03*
X513250Y574252D03*
X552000Y686000D03*
X542000Y764000D03*
X500000Y800000D03*
X564026Y850100D03*
X569026D03*
X513500Y1009000D03*
X553000Y1028500D03*
X570500Y1026000D03*
X569900Y1038500D03*
X546500Y1046000D03*
X513250Y1028500D03*
X484074Y1036831D03*
Y1026831D03*
X561250Y1004000D03*
X571000Y993000D03*
X576000D03*
X534000Y1068000D03*
X550000Y1100000D03*
X491074Y1105453D03*
X484074Y1066831D03*
Y1056831D03*
X500000Y1150000D03*
X550000D03*
Y1200000D03*
X500000D03*
X522000Y1294000D03*
X498000Y1332985D03*
X510000Y1344485D03*
X498000Y1352985D03*
X522000Y1344485D03*
X498000Y1342985D03*
X510000Y1354485D03*
X522000D03*
X510000Y1364485D03*
X522000D03*
X510000Y1374485D03*
Y1384485D03*
X522000Y1374485D03*
Y1384485D03*
X498000Y1382985D03*
Y1372985D03*
X486000Y1382985D03*
Y1372985D03*
X498000Y1362985D03*
X486000D03*
X501000Y1494000D03*
X503000Y1499000D03*
X494500Y1490500D03*
X574937Y1513685D03*
X569937D03*
X564937D03*
X559937D03*
X554937D03*
X549937D03*
X544937D03*
X539937D03*
X534937D03*
X529937D03*
X524937D03*
X483685Y1490063D03*
X488685D03*
X503244Y1504378D03*
Y1509378D03*
X504937Y1513685D03*
X509937D03*
X514937D03*
X528500Y1444600D03*
X519937Y1513685D03*
X500000Y1472000D03*
X507250Y1478000D03*
X585500Y45000D03*
X578000Y52000D03*
X592500Y28000D03*
X670412Y6000D03*
X665412D03*
X660412D03*
X655412D03*
X650412D03*
X645412D03*
X640412D03*
X635412D03*
X630412D03*
X625412D03*
X620412D03*
X615412D03*
X610412D03*
X605412D03*
X600412D03*
X595412D03*
X590412D03*
X585412D03*
X580412D03*
X608287Y66319D03*
Y51319D03*
X615287Y27697D03*
X581000Y87500D03*
X586000D03*
X644000Y558000D03*
X603787Y556024D03*
X586000Y540000D03*
X581000D03*
X664651Y513000D03*
X671000Y648000D03*
X672500Y615500D03*
X615287Y652697D03*
X622687Y614091D03*
X592500Y638500D03*
X586043Y615962D03*
X670500Y593000D03*
X622703Y604103D03*
X623005Y584047D03*
X608287Y574075D03*
X637750Y575500D03*
X590000Y680000D03*
X600000Y770000D03*
X650000D03*
X579148Y832411D03*
X656142Y831632D03*
X673000Y885500D03*
X578000Y1010500D03*
X625000Y1014500D03*
X670500Y1046000D03*
X637750Y1028500D03*
X608287Y1036831D03*
Y1026831D03*
X603787Y1008780D03*
X586000Y993000D03*
X581000D03*
X599000Y1115500D03*
X631500Y1112500D03*
X660000Y1068000D03*
X615287Y1105453D03*
X592500Y1091500D03*
X608287Y1066831D03*
Y1056831D03*
X586000Y1068200D03*
X672000Y1146000D03*
X670000Y1196000D03*
X581800Y1376500D03*
Y1384400D03*
Y1392300D03*
Y1360700D03*
Y1368600D03*
Y1352800D03*
Y1344900D03*
X589700Y1392300D03*
Y1400200D03*
Y1344900D03*
Y1352800D03*
Y1384400D03*
Y1376500D03*
Y1368600D03*
Y1360700D03*
X597600Y1400200D03*
Y1408100D03*
Y1360700D03*
Y1368600D03*
Y1392300D03*
Y1376500D03*
Y1384400D03*
Y1352800D03*
Y1344900D03*
X629200D03*
X621300D03*
X613400D03*
X605500D03*
Y1360700D03*
X613400D03*
X621300D03*
X629200D03*
X605500Y1352800D03*
X613400D03*
X621300D03*
X629200D03*
Y1368600D03*
Y1376500D03*
X605500Y1408100D03*
Y1400200D03*
Y1392300D03*
Y1384400D03*
Y1376500D03*
Y1368600D03*
X613400Y1400200D03*
Y1392300D03*
Y1384400D03*
Y1376500D03*
Y1368600D03*
X621300Y1376500D03*
Y1368600D03*
X613400Y1408100D03*
X669937Y1513685D03*
X659937D03*
X654937D03*
X649937D03*
X644937D03*
X639937D03*
X634937D03*
X629937D03*
X624937D03*
X619937D03*
X614937D03*
X609937D03*
X604937D03*
X599937D03*
X594937D03*
X589937D03*
X584937D03*
X579937D03*
X664937D03*
X653000Y1488500D03*
X765412Y6000D03*
X760412D03*
X755412D03*
X750412D03*
X745412D03*
X740412D03*
X735412D03*
X730412D03*
X725412D03*
X720412D03*
X715412D03*
X710412D03*
X705412D03*
X700412D03*
X695412D03*
X690412D03*
X685412D03*
X680412D03*
X675412D03*
X729201Y87285D03*
X727636Y93834D03*
X732500Y81319D03*
Y66319D03*
Y51319D03*
X739500Y27697D03*
X700000Y87500D03*
X705000D03*
X710000D03*
X694500D03*
X732500Y161319D03*
Y151319D03*
X747290Y118820D03*
X732500Y131319D03*
Y121319D03*
X728000Y103268D03*
X732087Y207847D03*
X685514Y397600D03*
X680514D03*
X716000Y568500D03*
X728000Y556024D03*
Y537126D03*
Y546575D03*
X688298Y551625D03*
X732500Y504075D03*
Y519075D03*
Y534075D03*
X724600Y487100D03*
X695000Y540000D03*
X700000D03*
X705000D03*
X710000D03*
X747843Y612115D03*
X739500Y652697D03*
X710300Y635400D03*
Y615200D03*
X748200Y572200D03*
X732500Y574075D03*
X694200Y585500D03*
X732500Y584075D03*
X694500Y573000D03*
X746356Y604075D03*
X710000Y760500D03*
X726500Y681500D03*
X693500Y680000D03*
X712000Y720000D03*
X680526Y850100D03*
X685526D03*
X739500Y933209D03*
X677000Y885500D03*
Y1028500D03*
X702500Y1010500D03*
X753050Y1028500D03*
X694500Y1026000D03*
X694000Y1038500D03*
X732500Y1036831D03*
Y1026831D03*
X730900Y955800D03*
X685250Y1004000D03*
X728000Y1008780D03*
Y989882D03*
Y999331D03*
X732500Y986831D03*
Y971831D03*
X700000Y993000D03*
X705000D03*
X710000D03*
X695000D03*
X750000Y1084000D03*
X698000Y1102000D03*
X739500Y1105453D03*
X716500Y1091500D03*
X710300Y1068200D03*
X732500Y1066831D03*
Y1056831D03*
X738000Y1152000D03*
X740000Y1202000D03*
X748000Y1170000D03*
X746000Y1218000D03*
X700000Y1150000D03*
X768867Y1311110D03*
Y1335110D03*
Y1327110D03*
Y1319110D03*
Y1383110D03*
Y1359110D03*
Y1367110D03*
Y1351110D03*
Y1343110D03*
Y1391110D03*
Y1399110D03*
Y1375110D03*
X724248Y1465560D03*
X722000Y1503500D03*
X718500Y1500000D03*
X680500Y1503500D03*
X674937Y1513685D03*
X688012Y1499118D03*
X693012D03*
X698012D03*
X703012D03*
X708012D03*
X713012D03*
X724000Y1509500D03*
X725551Y1513685D03*
X730551D03*
X735551D03*
X740551D03*
X745551D03*
X750551D03*
X755551D03*
X760551D03*
X765551D03*
X730500Y1451500D03*
X685850Y1468600D03*
X724000Y1439700D03*
X717600Y1449700D03*
X746832Y1451034D03*
X735232Y1439334D03*
X739332Y1462234D03*
X750867Y1438001D03*
X722200Y1476900D03*
X678500Y1510500D03*
X777465Y93947D03*
Y88947D03*
Y83947D03*
Y78947D03*
Y73947D03*
Y68947D03*
Y63947D03*
Y58947D03*
Y53947D03*
Y48947D03*
Y43947D03*
Y38947D03*
Y33947D03*
Y28947D03*
Y23947D03*
Y18947D03*
Y13947D03*
X778000Y9500D03*
X775412Y6000D03*
X770412D03*
X777465Y183947D03*
Y178947D03*
Y173947D03*
Y168947D03*
Y163947D03*
Y158947D03*
Y153947D03*
Y148947D03*
Y143947D03*
Y138947D03*
Y133947D03*
Y128947D03*
Y123947D03*
Y118947D03*
Y113947D03*
Y108947D03*
Y103947D03*
Y98947D03*
X862205Y282283D03*
X848032D03*
X833859D03*
X862205Y268110D03*
X848032D03*
X833859D03*
X862205Y253937D03*
X848032D03*
X833859D03*
X855118Y272835D03*
X840945D03*
X826772D03*
X771500Y251000D03*
X802000Y263500D03*
X809500Y197500D03*
X805522Y195764D03*
X808961Y201678D03*
Y206678D03*
Y211678D03*
Y216678D03*
Y236678D03*
Y231678D03*
Y226678D03*
Y221678D03*
Y241678D03*
X779022Y190764D03*
X784022Y194764D03*
X800522Y195764D03*
X795522D03*
X790522D03*
X862205Y310630D03*
X848032D03*
X833859D03*
X862205Y296457D03*
X848032D03*
X833859D03*
X855118Y315354D03*
X840945D03*
X826772D03*
X855118Y301181D03*
X840945D03*
X826772D03*
X855118Y287008D03*
X840945D03*
X826772D03*
X804500Y379000D03*
X769500Y431500D03*
X776867Y1311110D03*
Y1335110D03*
Y1327110D03*
Y1319110D03*
X775600Y1302400D03*
X790056Y1297863D03*
X798056D03*
X782056D03*
X834000Y1324500D03*
Y1317500D03*
Y1310500D03*
Y1303500D03*
X827000D03*
X820000D03*
X827000Y1310500D03*
X820000D03*
X827000Y1317500D03*
X820000D03*
X827000Y1324500D03*
X820000D03*
X776867Y1399110D03*
X790330Y1407929D03*
X782330D03*
X798330D03*
X795000Y1377900D03*
X786600Y1378100D03*
X790950Y1372703D03*
X776867Y1383110D03*
Y1359110D03*
X782950Y1372703D03*
X776867Y1367110D03*
Y1375110D03*
X798950Y1372703D03*
X776867Y1391110D03*
X790223Y1339930D03*
X782223Y1339430D03*
X798223Y1339930D03*
X776867Y1351110D03*
Y1343110D03*
X834000Y1386000D03*
Y1379000D03*
Y1363000D03*
Y1356000D03*
Y1349000D03*
Y1342000D03*
X827000D03*
X820000D03*
X827000Y1349000D03*
X820000D03*
X827000Y1356000D03*
X820000D03*
X827000Y1363000D03*
X820000D03*
X827000Y1379000D03*
X820000D03*
X827000Y1386000D03*
X820000D03*
X827000Y1393000D03*
X820000D03*
Y1448000D03*
X779500Y1491000D03*
X775000Y1495500D03*
X770551Y1513685D03*
X773528Y1510662D03*
Y1505662D03*
Y1500662D03*
X786803Y1490063D03*
X791803D03*
X796803D03*
X801803D03*
X806803D03*
X811803D03*
X816803D03*
X821803D03*
X826803D03*
X831803D03*
X836803D03*
X841803D03*
X846803D03*
X851803D03*
X856803D03*
X861803D03*
X876378Y282283D03*
Y268110D03*
Y253937D03*
X869292Y272835D03*
X887127Y254031D03*
X911811Y310630D03*
X876378D03*
Y296457D03*
X869292Y315354D03*
Y301181D03*
Y287008D03*
X958200Y1303900D03*
X942400D03*
X950300D03*
X934500D03*
X926600D03*
X958200Y1311800D03*
X926600D03*
X934500D03*
X950300D03*
X942400D03*
X903500Y1319400D03*
X950300Y1319700D03*
X958200D03*
X934500D03*
X942400D03*
X926600D03*
X918700D03*
X910800D03*
X887800Y1327100D03*
X934700Y1327500D03*
X895200D03*
X903100D03*
X911000D03*
X926800D03*
X918900D03*
X887800Y1335000D03*
X926000Y1420000D03*
X945200Y1398300D03*
Y1393500D03*
X950200Y1394500D03*
X886400Y1368100D03*
Y1376000D03*
X894300D03*
Y1368100D03*
X934700Y1335400D03*
X926800D03*
X918900D03*
X895200D03*
X903100D03*
X911000D03*
X890400Y1358900D03*
X887800Y1350800D03*
Y1342900D03*
X937300Y1359300D03*
X934700Y1343300D03*
Y1351200D03*
X926800Y1343300D03*
Y1351200D03*
X929400Y1359300D03*
X918900Y1343300D03*
Y1351200D03*
X921500Y1359300D03*
X918000Y1368100D03*
Y1376000D03*
X910100Y1368100D03*
Y1376000D03*
X911000Y1343300D03*
Y1351200D03*
X913600Y1359300D03*
X903100Y1343300D03*
Y1351200D03*
X905700Y1359300D03*
X902200Y1376000D03*
Y1368100D03*
X897800Y1359300D03*
X895200Y1351200D03*
Y1343300D03*
X866000Y1398000D03*
Y1452000D03*
X900000Y1450000D03*
X866803Y1490063D03*
X871803D03*
X876803D03*
X881803D03*
X886803D03*
X891803D03*
X896803D03*
X901803D03*
X906803D03*
X911803D03*
X916803D03*
X921803D03*
X926803D03*
X931803D03*
X936803D03*
X941803D03*
X946803D03*
X951803D03*
X956803D03*
X1035943Y1424649D03*
X1031443Y1426899D03*
X1040127Y1422500D03*
X1022818Y1393489D03*
X997000Y1496000D03*
X993000Y1491500D03*
X961803Y1490063D03*
X966803D03*
X971803D03*
X976803D03*
X981803D03*
X986803D03*
X998126Y1503614D03*
Y1508614D03*
Y1513614D03*
X1003126D03*
X1008126D03*
X1013126D03*
X1018126D03*
X1023126D03*
X1028126D03*
X1033126D03*
X1038126D03*
X1043126D03*
X1048126D03*
X1053126D03*
X1038303Y1441709D03*
X1021818Y1470865D03*
X1021693Y1444649D03*
X993100Y1456550D03*
X1007618Y1477365D03*
X1013418Y1470865D03*
X1027288Y1467441D03*
X1034100Y1500564D03*
X1024175Y1482189D03*
X1089000Y217500D03*
X1150000Y250000D03*
X1100000D03*
X1068734Y195764D03*
X1064500Y197500D03*
X1065055Y201895D03*
Y206895D03*
Y211895D03*
Y216895D03*
X1148734Y195764D03*
X1143734D03*
X1138734D03*
X1133734D03*
X1128734D03*
X1123734D03*
X1118734D03*
X1113734D03*
X1103734D03*
X1098734D03*
X1093734D03*
X1088734D03*
X1083734D03*
X1078734D03*
X1073734D03*
X1075627Y374973D03*
X1075829Y380885D03*
X1076142Y386839D03*
X1137600Y527100D03*
X1137446Y541317D03*
Y555490D03*
Y569663D03*
Y698798D03*
Y712971D03*
Y727144D03*
Y741317D03*
Y755490D03*
Y769663D03*
Y783836D03*
Y798010D03*
Y812183D03*
Y826356D03*
Y840529D03*
Y854703D03*
Y868876D03*
Y883049D03*
Y897222D03*
Y911396D03*
Y925569D03*
Y939742D03*
X1100625Y1292025D03*
X1107000Y1323500D03*
X1114000Y1430000D03*
X1087933Y1411323D03*
X1082933D03*
X1077933D03*
X1095567Y1426057D03*
X1058126Y1513614D03*
X1061675Y1510352D03*
X1065210Y1506817D03*
X1066638Y1472408D03*
Y1467408D03*
Y1462408D03*
Y1457408D03*
Y1452408D03*
Y1447408D03*
Y1442408D03*
X1095567Y1431057D03*
Y1436057D03*
Y1441057D03*
Y1446057D03*
Y1451057D03*
Y1456057D03*
Y1461057D03*
Y1466057D03*
X1096039Y1505861D03*
X1099575Y1509397D03*
X1103110Y1512932D03*
X1107798Y1513685D03*
X1112798D03*
X1117798D03*
X1122798D03*
X1127798D03*
X1132798D03*
X1137798D03*
X1142798D03*
X1147798D03*
X1095567Y1471057D03*
X1066638Y1502408D03*
X1234500Y6000D03*
X1243844D03*
X1238844D03*
X1230409Y7565D03*
Y12565D03*
Y17565D03*
Y22565D03*
Y27565D03*
Y32565D03*
Y37565D03*
Y42565D03*
Y47565D03*
Y52565D03*
Y57565D03*
Y62565D03*
Y67565D03*
Y72565D03*
Y77565D03*
Y82565D03*
Y87565D03*
Y92565D03*
X1238000Y164000D03*
X1230409Y97565D03*
Y102565D03*
Y107565D03*
Y112565D03*
Y117565D03*
Y122565D03*
Y127565D03*
Y132565D03*
Y137565D03*
Y142565D03*
Y147565D03*
Y152565D03*
Y157565D03*
Y162565D03*
Y167565D03*
Y172565D03*
Y177565D03*
Y182565D03*
X1236500Y216000D03*
X1200000Y250000D03*
X1218734Y195764D03*
X1213734D03*
X1208734D03*
X1203734D03*
X1198734D03*
X1193734D03*
X1188734D03*
X1183734D03*
X1178734D03*
X1173734D03*
X1168734D03*
X1163734D03*
X1158734D03*
X1153734D03*
X1196000Y1366000D03*
X1212000D03*
X1242000Y1412000D03*
X1226000Y1436000D03*
X1238000Y1444000D03*
X1190000Y1494000D03*
X1156000D03*
X1200000Y1450000D03*
X1245500Y1500500D03*
X1208000Y1502500D03*
X1234783Y1499118D03*
X1229783D03*
X1224783D03*
X1219783D03*
X1214783D03*
X1239783D03*
X1152798Y1513685D03*
X1157798D03*
X1162798D03*
X1167798D03*
X1172798D03*
X1177798D03*
X1182798D03*
X1187798D03*
X1192798D03*
X1197798D03*
X1202798D03*
X1205500Y1509000D03*
X1279400Y68650D03*
X1266400D03*
X1338844Y6000D03*
X1333844D03*
X1328844D03*
X1323844D03*
X1318844D03*
X1313844D03*
X1308844D03*
X1303844D03*
X1298844D03*
X1293844D03*
X1288844D03*
X1283844D03*
X1278844D03*
X1273844D03*
X1268844D03*
X1263844D03*
X1258844D03*
X1253844D03*
X1248844D03*
X1298655Y59926D03*
X1282106Y81319D03*
Y66319D03*
X1299800Y56000D03*
X1278038Y93821D03*
X1278698Y84340D03*
X1307200Y45000D03*
X1289106Y27697D03*
X1282106Y51319D03*
X1303500Y35000D03*
X1309500Y76500D03*
X1314500D03*
X1299500D03*
X1304500D03*
X1262000Y174000D03*
X1313000Y185500D03*
X1282106Y161319D03*
Y151319D03*
X1305000Y185500D03*
X1298500D03*
X1282106Y131319D03*
Y121319D03*
X1266600Y119500D03*
X1262468Y103268D03*
X1272500Y213000D03*
X1307500Y205000D03*
X1338000Y225000D03*
X1289106Y199941D03*
X1252000Y358000D03*
X1294500Y331500D03*
X1278500Y313000D03*
X1259445Y379019D03*
X1337824Y379176D03*
X1317500Y435500D03*
X1281693Y473218D03*
X1298500Y562500D03*
X1317500Y533500D03*
X1307500Y501500D03*
X1299900Y534200D03*
X1311200Y511500D03*
X1303800Y522500D03*
X1327000Y487000D03*
X1318000Y660000D03*
X1312973Y643128D03*
X1305000Y638500D03*
X1298000Y638300D03*
X1314000Y603500D03*
X1302500Y605000D03*
X1312000Y812000D03*
X1310000Y860000D03*
X1298000Y1014000D03*
X1318000Y986000D03*
X1300600Y986800D03*
X1307500Y954000D03*
X1311200Y964000D03*
X1303800Y975000D03*
X1314000Y1056000D03*
X1313000Y1091000D03*
X1298500D03*
X1302500Y1057500D03*
X1305000Y1091000D03*
X1288000Y1296000D03*
X1274000Y1314000D03*
X1300000Y1388000D03*
X1274000Y1374000D03*
X1318540Y1424331D03*
X1249000Y1504500D03*
X1328464Y1513685D03*
X1333464D03*
X1338464D03*
X1293464D03*
X1298464D03*
X1303464D03*
X1308464D03*
X1313464D03*
X1318464D03*
X1323464D03*
X1250500Y1510500D03*
X1253464Y1513685D03*
X1258464D03*
X1263464D03*
X1268464D03*
X1273464D03*
X1278464D03*
X1283464D03*
X1306625Y1434000D03*
X1303874Y1453750D03*
X1292374Y1452500D03*
X1301534Y1431345D03*
X1289124Y1430700D03*
X1253374Y1459300D03*
X1260874Y1481400D03*
X1264774Y1470700D03*
X1266574Y1452300D03*
X1288464Y1513685D03*
X1432000Y30000D03*
X1433844Y6000D03*
X1428844D03*
X1423844D03*
X1418844D03*
X1413844D03*
X1408844D03*
X1403844D03*
X1398844D03*
X1393844D03*
X1388844D03*
X1383844D03*
X1378844D03*
X1373844D03*
X1368844D03*
X1363844D03*
X1358844D03*
X1353844D03*
X1348844D03*
X1343844D03*
X1413319Y27697D03*
X1352000Y516000D03*
X1432000Y482000D03*
X1364000Y492000D03*
X1406319Y504075D03*
X1413319Y480453D03*
X1424400Y534200D03*
X1431500Y501500D03*
X1435200Y511500D03*
X1427800Y522500D03*
X1345215Y533601D03*
X1367500Y851922D03*
X1362500D03*
X1391000Y1024800D03*
X1406319Y1036831D03*
Y1026831D03*
X1360000Y1054000D03*
X1350000Y1100000D03*
X1413319Y1105453D03*
X1426500Y1057500D03*
X1422500Y1091000D03*
X1429000D03*
X1406319Y1066831D03*
Y1056831D03*
X1350000Y1150000D03*
X1400000D03*
Y1200000D03*
X1350000D03*
X1366000Y1388000D03*
X1385474Y1429500D03*
X1380074D03*
X1383374Y1425000D03*
X1383674Y1419000D03*
X1406000Y1444000D03*
X1433500Y1490500D03*
X1428500Y1494000D03*
X1403500Y1513500D03*
X1398500D03*
X1363464Y1513685D03*
X1368464D03*
X1373464D03*
X1378464D03*
X1383464D03*
X1388464D03*
X1393464D03*
X1353464D03*
X1358464D03*
X1343464D03*
X1348464D03*
X1408464D03*
X1413464D03*
X1418464D03*
X1423464D03*
X1425890Y1510111D03*
Y1505111D03*
Y1500111D03*
X1508000Y36000D03*
X1468000Y42000D03*
X1528844Y6000D03*
X1523844D03*
X1518844D03*
X1513844D03*
X1508844D03*
X1503844D03*
X1498844D03*
X1493844D03*
X1488844D03*
X1483844D03*
X1478844D03*
X1473844D03*
X1468844D03*
X1463844D03*
X1458844D03*
X1453844D03*
X1448844D03*
X1443844D03*
X1438844D03*
X1442500Y532000D03*
X1510000Y488000D03*
X1476000Y518000D03*
X1530531Y504075D03*
X1493500Y853100D03*
X1487000Y851600D03*
X1480000Y1020000D03*
X1515400Y1025000D03*
X1530531Y1036831D03*
Y1026831D03*
X1500000Y1100000D03*
X1530531Y1066831D03*
Y1056831D03*
X1437000Y1091000D03*
X1438000Y1056000D03*
X1450000Y1150000D03*
X1500000D03*
Y1200000D03*
X1450000D03*
X1500000Y1300000D03*
X1450000D03*
Y1350000D03*
X1500000D03*
Y1450000D03*
X1450000D03*
X1439716Y1490063D03*
X1444716D03*
X1449716D03*
X1454716D03*
X1459716D03*
X1464716D03*
X1469716D03*
X1474716D03*
X1479716D03*
X1484716D03*
X1489716D03*
X1494716D03*
X1499716D03*
X1504716D03*
X1509716D03*
X1514716D03*
X1519716D03*
X1524716D03*
X1529716D03*
X1574000Y26000D03*
X1623844Y6000D03*
X1618844D03*
X1613844D03*
X1608844D03*
X1603844D03*
X1598844D03*
X1593844D03*
X1588844D03*
X1583844D03*
X1578844D03*
X1573844D03*
X1568844D03*
X1563844D03*
X1558844D03*
X1553844D03*
X1548844D03*
X1543844D03*
X1538844D03*
X1533844D03*
X1553000Y35000D03*
X1537531Y27697D03*
X1549000Y76500D03*
X1554000D03*
X1564000D03*
X1559000D03*
X1611014Y397100D03*
X1616014D03*
X1594000Y506000D03*
X1558000Y482000D03*
X1559700Y511500D03*
X1556000Y501500D03*
X1552300Y522500D03*
X1537531Y480453D03*
X1616000Y850100D03*
X1611000D03*
X1604000Y1022000D03*
X1561500Y1091000D03*
X1553500D03*
X1600000Y1100000D03*
X1537531Y1105453D03*
X1551000Y1057500D03*
X1547000Y1091000D03*
X1562500Y1056000D03*
X1600000Y1200000D03*
Y1150000D03*
X1550000Y1300000D03*
X1600000D03*
X1550000Y1350000D03*
X1600000D03*
Y1450000D03*
X1550000D03*
X1534716Y1490063D03*
X1539716D03*
X1544716D03*
X1549716D03*
X1554716D03*
X1559716D03*
X1564716D03*
X1569716D03*
X1574716D03*
X1579716D03*
X1584716D03*
X1589716D03*
X1594716D03*
X1599716D03*
X1604716D03*
X1609716D03*
X1614716D03*
X1619716D03*
X1624716D03*
X1680000Y26000D03*
X1632000D03*
X1718844Y6000D03*
X1713844D03*
X1708844D03*
X1703844D03*
X1698844D03*
X1693844D03*
X1688844D03*
X1683844D03*
X1678844D03*
X1673844D03*
X1668844D03*
X1663844D03*
X1658844D03*
X1653844D03*
X1648844D03*
X1643844D03*
X1638844D03*
X1633844D03*
X1628844D03*
X1661744Y27697D03*
X1648000Y468000D03*
X1650244Y546575D03*
Y556024D03*
Y537126D03*
X1654744Y534075D03*
Y504075D03*
X1661744Y480453D03*
X1706000Y646000D03*
X1654744Y584075D03*
X1652808Y574040D03*
X1686500Y603500D03*
X1675000Y605000D03*
X1638200Y572200D03*
X1639100Y1024900D03*
X1654744Y1036831D03*
Y1026831D03*
X1638000Y1082000D03*
X1696000Y1106000D03*
X1661744Y1105453D03*
X1677500Y1091000D03*
X1686500Y1056000D03*
X1671000Y1091000D03*
X1675000Y1057500D03*
X1685500Y1091000D03*
X1654744Y1066831D03*
Y1056831D03*
X1650000Y1150000D03*
X1700000D03*
Y1200000D03*
X1650000D03*
Y1300000D03*
X1674000Y1410000D03*
X1650000Y1350000D03*
X1669376Y1429200D03*
X1649500Y1497500D03*
X1646000Y1492000D03*
X1720968Y1513685D03*
X1715968D03*
X1710968D03*
X1705968D03*
X1700968D03*
X1695968D03*
X1690968D03*
X1685968D03*
X1680968D03*
X1670968D03*
X1675968D03*
X1629716Y1490063D03*
X1634716D03*
X1639716D03*
X1650488Y1504165D03*
Y1509165D03*
X1650968Y1513685D03*
X1655968D03*
X1660968D03*
X1665968D03*
X1694751Y1434000D03*
X1683926Y1453750D03*
X1672626Y1452500D03*
X1686226Y1432500D03*
X1756000Y25500D03*
X1813844Y6000D03*
X1808844D03*
X1803844D03*
X1798844D03*
X1793844D03*
X1788844D03*
X1783844D03*
X1778844D03*
X1773844D03*
X1768844D03*
X1763844D03*
X1758844D03*
X1753844D03*
X1748844D03*
X1743844D03*
X1738844D03*
X1733844D03*
X1728844D03*
X1723844D03*
X1785956Y27697D03*
X1778956Y51319D03*
X1796300Y85600D03*
X1806300D03*
X1811300D03*
X1801300D03*
X1735014Y397100D03*
X1740014D03*
X1776250Y521406D03*
X1763250D03*
X1796000Y566500D03*
X1728000Y554000D03*
X1757200Y558900D03*
X1730000Y568000D03*
X1774456Y556024D03*
X1767342Y533721D03*
X1774456Y546575D03*
X1785728Y538736D03*
X1778956Y519075D03*
X1818000Y656000D03*
X1762000Y628000D03*
X1756000Y646000D03*
X1785956Y652697D03*
X1795000Y638500D03*
X1801500D03*
X1809500D03*
X1778956Y614075D03*
X1810500Y603500D03*
X1799000Y605000D03*
X1778956Y604075D03*
Y584075D03*
Y574075D03*
X1759750Y576000D03*
X1756000Y684000D03*
X1740000Y850100D03*
X1735000D03*
X1763300Y1024800D03*
X1778956Y1036831D03*
Y1026831D03*
X1730000Y1050000D03*
X1762000Y1080000D03*
X1785956Y1105453D03*
X1809500Y1091000D03*
X1801500D03*
X1810500Y1056000D03*
X1795000Y1091000D03*
X1799000Y1057500D03*
X1778956Y1066831D03*
Y1056831D03*
X1750000Y1150000D03*
Y1200000D03*
X1800000Y1300000D03*
Y1250000D03*
X1760000Y1394000D03*
X1800000Y1350000D03*
X1766526Y1429400D03*
X1760326Y1429500D03*
X1763926Y1419000D03*
X1763626Y1425000D03*
X1786004Y1513500D03*
X1780968Y1513685D03*
X1775968D03*
X1770968D03*
X1765968D03*
X1760968D03*
X1755968D03*
X1750968D03*
X1745968D03*
X1740968D03*
X1796004Y1513500D03*
X1801004D03*
X1806004D03*
X1811004D03*
X1816004D03*
X1730968Y1513685D03*
X1725968D03*
X1791004Y1513500D03*
X1735968Y1513685D03*
X1790226Y1458600D03*
X1803426Y1452600D03*
X1804326Y1480500D03*
X1794226Y1473300D03*
X1913844Y6000D03*
X1908844D03*
X1903844D03*
X1898844D03*
X1893844D03*
X1888844D03*
X1883844D03*
X1878844D03*
X1873844D03*
X1868844D03*
X1863844D03*
X1858844D03*
X1853844D03*
X1848844D03*
X1843844D03*
X1838844D03*
X1833844D03*
X1828844D03*
X1823844D03*
X1818844D03*
X1898669Y93819D03*
Y84370D03*
X1903169Y81319D03*
Y51319D03*
X1910169Y27697D03*
X1887900Y41300D03*
X1878000Y29300D03*
X1821850Y35400D03*
X1824200Y23400D03*
Y19000D03*
X1875500Y87000D03*
X1880500D03*
X1865500D03*
X1870500D03*
X1903169Y151319D03*
Y161319D03*
Y121319D03*
Y131319D03*
X1898669Y103268D03*
X1900000Y250000D03*
X1910169Y199941D03*
X1900000Y300000D03*
Y350000D03*
Y400000D03*
Y450000D03*
X1827114Y397900D03*
X1832114D03*
X1900463Y521406D03*
X1887463D03*
X1875000Y558000D03*
X1898669Y546575D03*
Y556024D03*
Y537126D03*
X1903169Y534075D03*
Y519075D03*
X1870500Y540500D03*
X1865500D03*
X1880500D03*
X1875500D03*
X1851400Y623800D03*
X1850000Y650000D03*
X1910169Y652697D03*
X1903169Y614075D03*
X1880500Y615200D03*
X1887000Y638500D03*
X1903169Y604075D03*
Y584075D03*
Y574075D03*
X1865000Y573000D03*
X1864700Y585500D03*
X1841000Y593000D03*
X1846000Y686000D03*
X1900000Y750000D03*
Y700000D03*
Y800000D03*
X1859500Y850100D03*
X1864500D03*
X1826000Y1036500D03*
X1864500Y1038500D03*
X1865000Y1026000D03*
X1903169Y1036831D03*
Y1026831D03*
X1841000Y1046000D03*
X1865500Y993000D03*
X1881814Y993136D03*
X1876814D03*
X1871814D03*
X1850000Y1078000D03*
X1910169Y1105453D03*
X1887000Y1091500D03*
X1880500Y1068200D03*
X1903169Y1066831D03*
Y1056831D03*
X1850000Y1200000D03*
X1900000D03*
Y1150000D03*
X1850000D03*
X1900000Y1300000D03*
X1850000D03*
X1900000Y1250000D03*
X1850000D03*
X1900000Y1400000D03*
X1850000D03*
Y1350000D03*
X1900000D03*
X1904000Y1504000D03*
X1878000Y1484000D03*
X1822000Y1444000D03*
X1900000Y1450000D03*
X1869500Y1503500D03*
X1865500Y1500000D03*
X1829500Y1501500D03*
X1826500Y1506500D03*
X1855256Y1499118D03*
X1850256D03*
X1845256D03*
X1840256D03*
X1826040Y1513315D03*
X1821040D03*
X1835256Y1499118D03*
X1860256D03*
X1871157Y1509110D03*
X1871582Y1513685D03*
X1876582D03*
X1881582D03*
X1886582D03*
X1891582D03*
X1896582D03*
X1901582D03*
X1906582D03*
X1911582D03*
X1928843Y8985D03*
Y93985D03*
Y88985D03*
Y83985D03*
Y78985D03*
Y73985D03*
Y68985D03*
Y63985D03*
Y58985D03*
Y53985D03*
Y48985D03*
Y43985D03*
Y38985D03*
Y28985D03*
Y23985D03*
Y18985D03*
Y13985D03*
Y33985D03*
X1923844Y6000D03*
X1918844D03*
X1928843Y98985D03*
Y188985D03*
Y183985D03*
Y178985D03*
Y173985D03*
Y168985D03*
Y163985D03*
Y158985D03*
Y153985D03*
Y148985D03*
Y143985D03*
Y138985D03*
Y133985D03*
Y128985D03*
Y123985D03*
Y118985D03*
Y113985D03*
Y108985D03*
Y103985D03*
Y283985D03*
Y278985D03*
Y273985D03*
Y268985D03*
Y263985D03*
Y258985D03*
Y253985D03*
Y248985D03*
Y243985D03*
Y238985D03*
Y233985D03*
Y228985D03*
Y223985D03*
Y218985D03*
Y213985D03*
Y208985D03*
Y203985D03*
Y198985D03*
Y193985D03*
Y378985D03*
Y373985D03*
Y368985D03*
Y363985D03*
Y358985D03*
Y353985D03*
Y348985D03*
Y343985D03*
Y338985D03*
Y333985D03*
Y328985D03*
Y323985D03*
Y318985D03*
Y313985D03*
Y308985D03*
Y303985D03*
Y298985D03*
Y293985D03*
Y288985D03*
Y418985D03*
Y433985D03*
Y428985D03*
Y423985D03*
Y473985D03*
Y468985D03*
Y463985D03*
Y458985D03*
Y453985D03*
Y448985D03*
Y443985D03*
Y438985D03*
Y413985D03*
Y408985D03*
Y403985D03*
Y398985D03*
Y393985D03*
Y388985D03*
Y383985D03*
Y568985D03*
Y563985D03*
Y558985D03*
Y553985D03*
Y548985D03*
Y543985D03*
Y538985D03*
Y533985D03*
Y528985D03*
Y523985D03*
Y518985D03*
Y513985D03*
Y508985D03*
Y503985D03*
Y498985D03*
Y493985D03*
Y488985D03*
Y483985D03*
Y478985D03*
Y663985D03*
Y658985D03*
Y653985D03*
Y648985D03*
Y643985D03*
Y638985D03*
Y633985D03*
Y628985D03*
Y623985D03*
Y618985D03*
Y613985D03*
Y608985D03*
Y603985D03*
Y598985D03*
Y593985D03*
Y588985D03*
Y583985D03*
Y578985D03*
Y573985D03*
Y758985D03*
Y753985D03*
Y748985D03*
Y743985D03*
Y738985D03*
Y733985D03*
Y728985D03*
Y723985D03*
Y718985D03*
Y713985D03*
Y708985D03*
Y703985D03*
Y698985D03*
Y693985D03*
Y688985D03*
Y683985D03*
Y678985D03*
Y673985D03*
Y668985D03*
Y853985D03*
Y848985D03*
Y843985D03*
Y838985D03*
Y833985D03*
Y828985D03*
Y823985D03*
Y818985D03*
Y813985D03*
Y808985D03*
Y803985D03*
Y798985D03*
Y793985D03*
Y788985D03*
Y783985D03*
Y778985D03*
Y773985D03*
Y768985D03*
Y763985D03*
Y918985D03*
Y913985D03*
Y908985D03*
Y903985D03*
Y898985D03*
Y893985D03*
Y888985D03*
Y883985D03*
Y878985D03*
Y873985D03*
Y868985D03*
Y863985D03*
Y858985D03*
Y948985D03*
Y943985D03*
Y938985D03*
Y933985D03*
Y928985D03*
Y923985D03*
Y1043985D03*
Y1038985D03*
Y1033985D03*
Y1028985D03*
Y1023985D03*
Y1018985D03*
Y1013985D03*
Y1008985D03*
Y1003985D03*
Y998985D03*
Y993985D03*
Y988985D03*
Y983985D03*
Y978985D03*
Y973985D03*
Y968985D03*
Y963985D03*
Y958985D03*
Y953985D03*
Y1143985D03*
Y1138985D03*
Y1133985D03*
Y1128985D03*
Y1123985D03*
Y1118985D03*
Y1113985D03*
Y1108985D03*
Y1103985D03*
Y1098985D03*
Y1093985D03*
Y1088985D03*
Y1083985D03*
Y1078985D03*
Y1073985D03*
Y1068985D03*
Y1063985D03*
Y1058985D03*
Y1053985D03*
Y1048985D03*
Y1238985D03*
Y1233985D03*
Y1228985D03*
Y1223985D03*
Y1218985D03*
Y1213985D03*
Y1208985D03*
Y1203985D03*
Y1198985D03*
Y1193985D03*
Y1188985D03*
Y1183985D03*
Y1178985D03*
Y1173985D03*
Y1168985D03*
Y1163985D03*
Y1158985D03*
Y1153985D03*
Y1148985D03*
Y1288985D03*
Y1293985D03*
Y1298985D03*
Y1303985D03*
Y1308985D03*
Y1313985D03*
Y1318985D03*
Y1323985D03*
Y1328985D03*
Y1333985D03*
Y1283985D03*
Y1278985D03*
Y1273985D03*
Y1268985D03*
Y1263985D03*
Y1258985D03*
Y1253985D03*
Y1248985D03*
Y1243985D03*
Y1348985D03*
Y1353985D03*
Y1358985D03*
Y1363985D03*
Y1368985D03*
Y1373985D03*
Y1378985D03*
Y1383985D03*
Y1388985D03*
Y1393985D03*
Y1398985D03*
Y1403985D03*
Y1408985D03*
Y1413985D03*
Y1418985D03*
Y1423985D03*
Y1428985D03*
Y1338985D03*
Y1343985D03*
Y1448985D03*
Y1443985D03*
Y1433985D03*
Y1438985D03*
X1920000Y1458000D03*
X1917500Y1463500D03*
X1916582Y1513685D03*
X1917031Y1509134D03*
Y1504134D03*
Y1499134D03*
Y1494134D03*
Y1489134D03*
Y1484134D03*
Y1479134D03*
Y1474134D03*
Y1469134D03*
X1926500Y1455000D03*
G54D28*
X257687Y487212D03*
X261687D03*
G54D14*
X41263Y887025D03*
X48763D03*
X55763D03*
X51263Y894525D03*
X46763Y891525D03*
X178993Y455018D03*
Y451018D03*
X182827Y447764D03*
Y455764D03*
X186827D03*
X182827Y451764D03*
X186827D03*
X182827Y439764D03*
Y443764D03*
X188941Y472055D03*
X153590Y449289D03*
X146590D03*
X149090Y456789D03*
X144590Y453789D03*
X139090Y449289D03*
X164200Y885700D03*
X158900D03*
X192963Y888625D03*
Y883625D03*
X188163Y888625D03*
X183363D03*
X178563D03*
Y883625D03*
X173763D03*
Y888625D03*
X183363Y883625D03*
X188163D03*
X291500Y451100D03*
Y446100D03*
X286700D03*
Y451100D03*
X281900D03*
Y446100D03*
X272300D03*
Y451100D03*
X277100Y446100D03*
Y451100D03*
X257127Y448364D03*
X261927D03*
X266690Y479089D03*
Y483089D03*
X252490D03*
Y479089D03*
X197763Y888625D03*
Y883625D03*
X296300Y446100D03*
Y451100D03*
X666100Y1360800D03*
Y1368700D03*
Y1376600D03*
Y1352900D03*
X658200Y1360800D03*
Y1368700D03*
Y1376600D03*
Y1352900D03*
X666100Y1345000D03*
X658200D03*
X705600Y1360800D03*
Y1352900D03*
Y1345000D03*
Y1376600D03*
Y1368700D03*
X699600Y1408200D03*
Y1392400D03*
Y1400300D03*
X697700Y1345000D03*
Y1360800D03*
Y1368700D03*
Y1376600D03*
X697100Y1384600D03*
X697700Y1352900D03*
X691700Y1408200D03*
Y1400300D03*
X675900D03*
X683800D03*
Y1408200D03*
X675900D03*
X689800Y1352900D03*
Y1384500D03*
Y1376600D03*
X691700Y1392400D03*
X689800Y1368700D03*
Y1360800D03*
X674000D03*
X681900D03*
Y1368700D03*
X674000D03*
X675900Y1392400D03*
X683800D03*
X674000Y1376600D03*
X681900D03*
Y1384500D03*
X674000D03*
Y1352900D03*
X681900D03*
X689800Y1345000D03*
X681900D03*
X674000D03*
X1814463Y449725D03*
Y454725D03*
X1804900Y451800D03*
X1799600D03*
X1838463Y454725D03*
Y449725D03*
X1819263D03*
Y454725D03*
X1833663D03*
Y449725D03*
X1828863D03*
Y454725D03*
X1824063D03*
Y449725D03*
X1912663Y888925D03*
Y883925D03*
X1873800Y886300D03*
X1898263Y883925D03*
Y888925D03*
X1903063D03*
Y883925D03*
X1907863D03*
Y888925D03*
X1893463D03*
Y883925D03*
X1879100Y886300D03*
X1888663Y888925D03*
Y883925D03*
G54D26*
X184252Y1445275D03*
Y1466929D03*
X167716Y1445275D03*
Y1466929D03*
X233858Y1445275D03*
Y1466929D03*
X217322Y1445275D03*
Y1466929D03*
X200787Y1445275D03*
Y1466929D03*
X581102Y1445275D03*
Y1466929D03*
X564567Y1445275D03*
Y1466929D03*
X548031Y1445275D03*
Y1466929D03*
X614173Y1445275D03*
Y1466929D03*
X597637Y1445275D03*
Y1466929D03*
X1331496Y1445275D03*
Y1466929D03*
X1314960Y1445275D03*
Y1466929D03*
X1381102Y1445275D03*
Y1466929D03*
X1364566Y1445275D03*
Y1466929D03*
X1348031Y1445275D03*
Y1466929D03*
X1711811Y1445275D03*
Y1466929D03*
X1695275Y1445275D03*
Y1466929D03*
X1761417Y1445275D03*
Y1466929D03*
X1744881Y1445275D03*
Y1466929D03*
X1728346Y1445275D03*
Y1466929D03*
G54D10*
X59400Y32600D03*
X63374Y1454500D03*
X390757Y1511515D03*
X812347Y17406D03*
X885639Y1511515D03*
X1187163Y158305D03*
X1538001Y1511515D03*
X1869500Y1461500D03*
G54D20*
X173228Y55118D03*
X421653Y94488D03*
X670078Y55118D03*
X1343701D03*
X1592126Y94488D03*
X1840551Y55118D03*
G54D31*
X503248Y715748D03*
X1673917Y262992D03*
G54D29*
X246535Y1320472D03*
X531535D03*
G54D30*
X266535D03*
X511535D03*
G54D27*
X167716Y1495669D03*
X233858D03*
X548031D03*
X614173D03*
X1314960D03*
X1381102D03*
X1695275D03*
X1761417D03*
G54D23*
X173228Y122047D03*
X670079D03*
X1343701Y122046D03*
X1840551D03*
G54D37*
X1104528Y1162257D03*
G54D13*
X69942Y406555D03*
X57675Y851609D03*
X202500Y82500D03*
X369086Y1313208D03*
X374086D03*
X379086D03*
X384086D03*
X324086D03*
X329086D03*
X334086D03*
X339086D03*
X344086D03*
X349086D03*
X354086D03*
X359086D03*
X364086D03*
X294086D03*
X299086D03*
X304086D03*
X309086D03*
X319086D03*
X389086D03*
X394086D03*
X524236Y1463672D03*
X658200Y1329200D03*
X666100D03*
Y1337100D03*
X658200D03*
X699500Y82500D03*
X705600Y1329200D03*
X697700Y1321300D03*
Y1329200D03*
X689800D03*
Y1321300D03*
X693800Y1313900D03*
Y1306000D03*
X685900D03*
X678000D03*
Y1313900D03*
X685900D03*
X681900Y1321300D03*
X674000D03*
Y1329200D03*
X681900D03*
X693800Y1298000D03*
X685900D03*
X678000D03*
X705600Y1337100D03*
X697700D03*
X689800D03*
X681900D03*
X674000D03*
X974015Y284449D03*
X986614D03*
X1002362D03*
X1014960D03*
X1030709D03*
X1043307D03*
X1002362Y261812D03*
X1014960D03*
X1030709D03*
X1043307D03*
X974015Y278544D03*
X1002362D03*
X1030709D03*
X1002362Y267717D03*
X1030709D03*
X1002362Y255906D03*
X1030709D03*
X986614Y278544D03*
X1014960D03*
X1043307D03*
X1014960Y267717D03*
X1043307D03*
X1014960Y255906D03*
X1043307D03*
X974015Y307087D03*
X986614D03*
X974015Y312993D03*
Y301182D03*
Y290355D03*
X1002362D03*
X1030709D03*
X986614Y312993D03*
Y301182D03*
Y290355D03*
X1014960D03*
X1043307D03*
X1065055Y226895D03*
Y231895D03*
Y236895D03*
Y241895D03*
Y221895D03*
X1124612Y1388773D03*
X1130112Y1363273D03*
X1138112D03*
X1132112Y1380773D03*
X1114112Y1363273D03*
X1118112D03*
X1126112D03*
X1110512Y1403273D03*
X1229000Y189500D03*
X1225000Y194000D03*
X1178712Y1372573D03*
X1200962Y1413023D03*
X1209819Y1417377D03*
X1252750Y53650D03*
X1265250D03*
X1376963Y506406D03*
X1389463D03*
X1501175D03*
X1513675D03*
X1625388D03*
X1637888D03*
X1749600Y53650D03*
X1762100D03*
X1811700Y59550D03*
X1873813Y53650D03*
X1886313D03*
X1820200Y70140D03*
X1871400Y82000D03*
G54D21*
X148050Y20971D03*
X126900Y39500D03*
X150700Y33100D03*
X376413Y520075D03*
Y533075D03*
X373492Y1317441D03*
Y1322441D03*
Y1327441D03*
Y1332441D03*
X343688Y1317736D03*
Y1322736D03*
Y1327736D03*
Y1332736D03*
X313688D03*
Y1327736D03*
Y1322736D03*
Y1317736D03*
Y1312736D03*
X373492Y1337441D03*
Y1342441D03*
Y1347441D03*
Y1352441D03*
X343688Y1337736D03*
Y1342736D03*
Y1347736D03*
Y1352736D03*
X313688D03*
Y1347736D03*
Y1342736D03*
Y1337736D03*
X500625Y520075D03*
Y533075D03*
X505224Y1424156D03*
X624838Y520075D03*
Y533075D03*
X749051Y67319D03*
Y80319D03*
Y520075D03*
Y533075D03*
Y972831D03*
Y985831D03*
X855100Y258531D03*
X841000D03*
X826700D03*
X869300D03*
X1033287Y1410500D03*
X1091089Y520057D03*
X1105262D03*
X1119435D03*
X1133609D03*
X1095026Y527143D03*
X1109199D03*
X1123372D03*
X1091089Y534230D03*
X1105262D03*
X1119435D03*
X1133609D03*
X1095026Y541317D03*
X1109199D03*
X1123372D03*
X1091089Y548403D03*
X1105262D03*
X1119435D03*
X1133609D03*
X1095026Y555490D03*
X1109199D03*
X1123372D03*
X1091089Y562576D03*
X1105262D03*
X1119435D03*
X1133609D03*
X1095026Y569663D03*
X1109199D03*
X1123372D03*
X1091089Y691711D03*
Y705884D03*
Y720057D03*
Y734230D03*
Y748403D03*
Y762577D03*
X1105262Y691711D03*
Y705884D03*
Y720057D03*
Y734230D03*
Y748403D03*
Y762577D03*
X1119435Y691711D03*
Y705884D03*
Y720057D03*
Y734230D03*
Y748403D03*
Y762577D03*
X1133609Y691711D03*
Y705884D03*
Y720057D03*
Y734230D03*
Y748403D03*
Y762577D03*
X1095026Y698797D03*
Y712970D03*
Y727144D03*
Y741317D03*
Y755490D03*
X1109199Y698797D03*
Y712970D03*
Y727144D03*
Y741317D03*
Y755490D03*
X1123372Y698797D03*
Y712970D03*
Y727144D03*
Y741317D03*
Y755490D03*
X1091089Y776750D03*
Y790923D03*
Y805096D03*
Y819270D03*
Y833443D03*
Y847616D03*
X1105262Y776750D03*
Y790923D03*
Y805096D03*
Y819270D03*
Y833443D03*
Y847616D03*
X1119435Y776750D03*
Y790923D03*
Y805096D03*
Y819270D03*
Y833443D03*
Y847616D03*
X1133609Y776750D03*
Y790923D03*
Y805096D03*
Y819270D03*
Y833443D03*
Y847616D03*
X1095026Y769663D03*
Y783836D03*
Y798010D03*
Y812183D03*
Y826356D03*
Y840529D03*
Y854703D03*
X1109199Y769663D03*
Y783836D03*
Y798010D03*
Y812183D03*
Y826356D03*
Y840529D03*
Y854703D03*
X1123372Y769663D03*
Y783836D03*
Y798010D03*
Y812183D03*
Y826356D03*
Y840529D03*
Y854703D03*
X1091089Y861789D03*
Y875962D03*
Y890136D03*
Y904309D03*
Y918482D03*
Y932655D03*
X1105262Y861789D03*
Y875962D03*
Y890136D03*
Y904309D03*
Y918482D03*
Y932655D03*
X1119435Y861789D03*
Y875962D03*
Y890136D03*
Y904309D03*
Y918482D03*
Y932655D03*
X1133609Y861789D03*
Y875962D03*
Y890136D03*
Y904309D03*
Y918482D03*
Y932655D03*
X1095026Y868876D03*
Y883049D03*
Y897222D03*
Y911396D03*
Y925569D03*
Y939742D03*
X1109199Y868876D03*
Y883049D03*
Y897222D03*
Y911396D03*
Y925569D03*
Y939742D03*
X1123372Y868876D03*
Y883049D03*
Y897222D03*
Y911396D03*
Y925569D03*
Y939742D03*
X1130873Y1490848D03*
Y1495848D03*
X1223730Y1285803D03*
X1230600D03*
X1235600D03*
X1202394D03*
X1197394D03*
X1190524D03*
X1795600Y44900D03*
X1817500Y32700D03*
X1814850Y21500D03*
G54D25*
X169215Y876085D03*
Y880885D03*
X154215D03*
Y876085D03*
X169215Y895685D03*
Y890885D03*
X154215Y895685D03*
Y890885D03*
X251200Y457900D03*
Y438300D03*
Y443100D03*
Y453100D03*
X267752Y458160D03*
Y438560D03*
Y443360D03*
Y453360D03*
X1809915Y461785D03*
Y446985D03*
Y456985D03*
Y442185D03*
X1794915Y461785D03*
Y446985D03*
Y456985D03*
Y442185D03*
X1869115Y876385D03*
Y891185D03*
Y881185D03*
Y895985D03*
X1884115Y876385D03*
Y891185D03*
Y881185D03*
Y895985D03*
G54D32*
X581800Y1321200D03*
Y1329100D03*
X589700D03*
Y1321200D03*
X594800Y1313500D03*
X597600Y1321200D03*
Y1329100D03*
X610600Y1313500D03*
Y1305600D03*
Y1297600D03*
X602700Y1313500D03*
Y1305600D03*
Y1297600D03*
X629200Y1329100D03*
X605500Y1321200D03*
X613400D03*
X605500Y1329100D03*
X613400D03*
X621300D03*
X581800Y1337000D03*
X589700D03*
X597600D03*
X629200D03*
X613400D03*
X621300D03*
X605500D03*
G36*
G01X149667Y265962D02*
G02X112734I-18466J-14781D01*
G03X119307Y278426I-29176J23351D01*
G02X143094I11894J-3623D01*
G03X149667Y265962I35749J10887D01*
G37*
G36*
G01Y718718D02*
G02X112734I-18466J-14781D01*
G03X119307Y731182I-29176J23351D01*
G02X143094I11894J-3623D01*
G03X149667Y718718I35749J10887D01*
G37*
G36*
G01Y1171473D02*
G02X112734I-18466J-14781D01*
G03X119307Y1183937I-29176J23351D01*
G02X143094I11894J-3623D01*
G03X149667Y1171473I35749J10887D01*
G37*
G36*
G01X397699Y265962D02*
G02X360766I-18467J-14781D01*
G03X367339Y278426I-29176J23351D01*
G02X391126I11894J-3623D01*
G03X397699Y265962I35749J10887D01*
G37*
G36*
G01Y718718D02*
G02X360766I-18467J-14781D01*
G03X367339Y731182I-29176J23351D01*
G02X391126I11894J-3623D01*
G03X397699Y718718I35749J10887D01*
G37*
G36*
G01Y1171473D02*
G02X360766I-18467J-14781D01*
G03X367339Y1183937I-29176J23351D01*
G02X391126I11894J-3623D01*
G03X397699Y1171473I35749J10887D01*
G37*
G36*
G01X645730Y265962D02*
G02X608797I-18466J-14781D01*
G03X615370Y278426I-29176J23351D01*
G02X639157I11893J-3623D01*
G03X645730Y265962I35749J10887D01*
G37*
G36*
G01Y718718D02*
G02X608797I-18466J-14781D01*
G03X615370Y731182I-29176J23351D01*
G02X639157I11893J-3623D01*
G03X645730Y718718I35749J10887D01*
G37*
G36*
G01Y1171473D02*
G02X608797I-18466J-14781D01*
G03X615370Y1183937I-29176J23351D01*
G02X639157I11893J-3623D01*
G03X645730Y1171473I35749J10887D01*
G37*
G36*
G01X765711Y384859D02*
G02X728778I-18466J-14781D01*
G03X735351Y397323I-29176J23351D01*
G02X759138I11893J-3623D01*
G03X765711Y384859I35749J10887D01*
G37*
G36*
G01Y817930D02*
G02X728778I-18466J-14781D01*
G03X735351Y830394I-29176J23351D01*
G02X759138I11893J-3623D01*
G03X765711Y817930I35749J10887D01*
G37*
G36*
G01X979884Y706906D02*
G02X942951I-18467J-14781D01*
G03X949524Y719370I-29176J23351D01*
G02X973311I11894J-3623D01*
G03X979884Y706906I35749J10887D01*
G37*
G36*
G01Y975410D02*
G02X942951I-18467J-14781D01*
G03X949524Y987874I-29176J23351D01*
G02X973311I11894J-3623D01*
G03X979884Y975410I35749J10887D01*
G37*
G36*
G01X1200356Y384859D02*
G02X1163423I-18467J-14781D01*
G03X1169996Y397323I-29176J23351D01*
G02X1193783I11894J-3623D01*
G03X1200356Y384859I35749J10887D01*
G37*
G36*
G01Y975410D02*
G02X1163423I-18467J-14781D01*
G03X1169996Y987874I-29176J23351D01*
G02X1193783I11894J-3623D01*
G03X1200356Y975410I35749J10887D01*
G37*
G36*
G01X1320337Y265961D02*
G02X1283404I-18467J-14781D01*
G03X1289977Y278425I-29176J23351D01*
G02X1313764I11894J-3623D01*
G03X1320337Y265961I35749J10887D01*
G37*
G36*
G01Y718718D02*
G02X1283404I-18467J-14781D01*
G03X1289977Y731182I-29176J23351D01*
G02X1313764I11894J-3623D01*
G03X1320337Y718718I35749J10887D01*
G37*
G36*
G01Y1171473D02*
G02X1283404I-18467J-14781D01*
G03X1289977Y1183937I-29176J23351D01*
G02X1313764I11894J-3623D01*
G03X1320337Y1171473I35749J10887D01*
G37*
G36*
G01X1568368Y265962D02*
G02X1531435I-18467J-14781D01*
G03X1538008Y278426I-29176J23351D01*
G02X1561795I11894J-3623D01*
G03X1568368Y265962I35749J10887D01*
G37*
G36*
G01Y718718D02*
G02X1531435I-18467J-14781D01*
G03X1538008Y731182I-29176J23351D01*
G02X1561795I11894J-3623D01*
G03X1568368Y718718I35749J10887D01*
G37*
G36*
G01Y1171473D02*
G02X1531435I-18467J-14781D01*
G03X1538008Y1183937I-29176J23351D01*
G02X1561795I11894J-3623D01*
G03X1568368Y1171473I35749J10887D01*
G37*
G36*
G01X1816400Y265961D02*
G02X1779467I-18466J-14781D01*
G03X1786040Y278425I-29176J23351D01*
G02X1809827I11894J-3623D01*
G03X1816400Y265961I35749J10887D01*
G37*
G36*
G01Y718718D02*
G02X1779467I-18466J-14781D01*
G03X1786040Y731182I-29176J23351D01*
G02X1809827I11894J-3623D01*
G03X1816400Y718718I35749J10887D01*
G37*
G36*
G01Y1171473D02*
G02X1779467I-18466J-14781D01*
G03X1786040Y1183937I-29176J23351D01*
G02X1809827I11894J-3623D01*
G03X1816400Y1171473I35749J10887D01*
G37*
%LPC*%
G75*
G54D38*
G01X466941Y-145664D02*
Y-225664D01*
G01D02*
X1593241D01*
G01X462941Y-129664D02*
G02I-12000J0D01*
G01X457791D02*
G02I-6850J0D01*
G01X450941Y-145664D02*
Y-113664D01*
G01X466941Y-129664D02*
X434941D01*
G01X466941Y-145664D02*
X1593241D01*
G01X466941Y-181164D02*
X1593241D01*
G01X805741Y-145664D02*
Y-225664D01*
G01X943241Y-145664D02*
Y-225664D01*
G01X1058241Y-145664D02*
Y-225664D01*
G01X1225741Y-145664D02*
Y-225664D01*
G01X1395741Y-145664D02*
Y-225664D01*
G01X1593241Y-145664D02*
Y-225664D01*
G01X1621241Y-129664D02*
G02I-12000J0D01*
G01X1616091D02*
G02I-6850J0D01*
G01X1609241Y-145664D02*
Y-113664D01*
G01X1625241Y-129664D02*
X1593241D01*
G54D39*
G01X489037Y-206331D02*
X489911Y-205456D01*
X490566Y-203998D01*
X491003Y-201955D01*
X490566Y-200206D01*
X489693Y-199039D01*
X488164Y-198164D01*
X482269D01*
Y-215664D01*
X489474D01*
X491003Y-214498D01*
X491876Y-212747D01*
X492313Y-210706D01*
X491876Y-208664D01*
X490566Y-206914D01*
X489037Y-206331D01*
X482269D01*
G01X501734Y-215664D02*
Y-203998D01*
G01Y-206331D02*
X502826Y-205164D01*
X503918Y-204289D01*
X505446Y-203998D01*
X506537Y-204289D01*
X507848Y-205164D01*
G01X517706Y-220914D02*
X519016Y-221497D01*
X520763Y-220914D01*
X521854Y-219748D01*
X522728Y-218289D01*
X524037Y-213623D01*
X526876Y-203998D01*
G01X519889D02*
X524037Y-213623D01*
G01X543284Y-205456D02*
X541756Y-204289D01*
X540446Y-203998D01*
X538699Y-204581D01*
X537389Y-205747D01*
X536516Y-207789D01*
X536297Y-209831D01*
X536516Y-211873D01*
X537389Y-213623D01*
X538699Y-215081D01*
X540446Y-215664D01*
X541974Y-215081D01*
X543284Y-213914D01*
G01X554016Y-207789D02*
X561003D01*
X560348Y-205747D01*
X559256Y-204581D01*
X557728Y-203998D01*
X556199Y-204289D01*
X554889Y-205164D01*
X554016Y-207206D01*
X553579Y-208956D01*
Y-210706D01*
X554016Y-212456D01*
X555108Y-214206D01*
X556418Y-215372D01*
X557946Y-215664D01*
X559474Y-215081D01*
X561003Y-213331D01*
G01X597094Y-199623D02*
X595784Y-198747D01*
X594256Y-198164D01*
X592509D01*
X590544Y-199039D01*
X589016Y-200497D01*
X587924Y-202248D01*
X587051Y-205164D01*
X586832Y-207789D01*
X587269Y-210414D01*
X587924Y-212164D01*
X589234Y-213914D01*
X590763Y-215081D01*
X592291Y-215664D01*
X593819D01*
X595348Y-215081D01*
X596658Y-214206D01*
X597750Y-213040D01*
G01X613721Y-215664D02*
Y-203998D01*
G01Y-206039D02*
X612848Y-204873D01*
X611537Y-204289D01*
X610009Y-203998D01*
X608481Y-204581D01*
X607171Y-205747D01*
X606297Y-207497D01*
X605861Y-209831D01*
X606297Y-212164D01*
X607171Y-213914D01*
X608481Y-215081D01*
X610009Y-215664D01*
X611537Y-215372D01*
X612848Y-214498D01*
X613721Y-213331D01*
G01X623579Y-215664D02*
Y-203998D01*
G01Y-206914D02*
X624453Y-205456D01*
X625763Y-204289D01*
X627509Y-203998D01*
X629037Y-204289D01*
X630348Y-205456D01*
X631003Y-207497D01*
Y-215664D01*
G01X640206Y-220914D02*
X641516Y-221497D01*
X643263Y-220914D01*
X644354Y-219748D01*
X645228Y-218289D01*
X646537Y-213623D01*
X649376Y-203998D01*
G01X642389D02*
X646537Y-213623D01*
G01X662291Y-215664D02*
X660981Y-215372D01*
X659671Y-214206D01*
X658797Y-212164D01*
X658361Y-209831D01*
X658797Y-207497D01*
X659671Y-205456D01*
X660981Y-204289D01*
X662291Y-203998D01*
X663601Y-204289D01*
X664911Y-205456D01*
X665784Y-207497D01*
X666003Y-209831D01*
X665784Y-212164D01*
X664911Y-214206D01*
X663601Y-215372D01*
X662291Y-215664D01*
G01X676079D02*
Y-203998D01*
G01Y-206914D02*
X676953Y-205456D01*
X678263Y-204289D01*
X680009Y-203998D01*
X681537Y-204289D01*
X682848Y-205456D01*
X683503Y-207497D01*
Y-215664D01*
G01X710424D02*
Y-198164D01*
X715883D01*
X717629Y-199039D01*
X718721Y-200206D01*
X719158Y-202539D01*
X718721Y-204873D01*
X717411Y-206331D01*
X715883Y-207206D01*
X710424D01*
G01X715883D02*
X719158Y-215664D01*
G01X732291Y-216247D02*
X731854Y-215956D01*
Y-215372D01*
X732291Y-215081D01*
X732728Y-215372D01*
Y-215956D01*
X732291Y-216247D01*
G01X744988Y-215664D02*
Y-198164D01*
X749354D01*
X751101Y-199039D01*
X752411Y-200206D01*
X753503Y-201955D01*
X754376Y-203998D01*
X754594Y-206914D01*
X754376Y-209831D01*
X753503Y-211873D01*
X752411Y-213623D01*
X751101Y-214789D01*
X749354Y-215664D01*
X744988D01*
G01X762924D02*
Y-198164D01*
X768164D01*
X769911Y-199039D01*
X771221Y-201081D01*
X771658Y-203414D01*
X771221Y-205747D01*
X770129Y-207497D01*
X768164Y-208373D01*
X762924D01*
G01X786537Y-206331D02*
X787411Y-205456D01*
X788066Y-203998D01*
X788503Y-201955D01*
X788066Y-200206D01*
X787193Y-199039D01*
X785664Y-198164D01*
X779769D01*
Y-215664D01*
X786974D01*
X788503Y-214498D01*
X789376Y-212747D01*
X789813Y-210706D01*
X789376Y-208664D01*
X788066Y-206914D01*
X786537Y-206331D01*
X779769D01*
G01X595364Y-170664D02*
Y-153164D01*
X601041Y-167747D01*
X606718Y-153164D01*
Y-170664D01*
G01X618541D02*
X617231Y-170372D01*
X615921Y-169206D01*
X615047Y-167164D01*
X614611Y-164831D01*
X615047Y-162497D01*
X615921Y-160456D01*
X617231Y-159289D01*
X618541Y-158998D01*
X619851Y-159289D01*
X621161Y-160456D01*
X622034Y-162497D01*
X622253Y-164831D01*
X622034Y-167164D01*
X621161Y-169206D01*
X619851Y-170372D01*
X618541Y-170664D01*
G01X639971Y-153164D02*
Y-170664D01*
G01Y-168040D02*
X639098Y-169498D01*
X637787Y-170372D01*
X636259Y-170664D01*
X634513Y-170081D01*
X633203Y-168623D01*
X632329Y-166873D01*
X632111Y-164831D01*
X632329Y-162789D01*
X633203Y-161039D01*
X634513Y-159581D01*
X636259Y-158998D01*
X637787Y-159289D01*
X638879Y-159873D01*
X639971Y-161039D01*
G01X650266Y-162789D02*
X657253D01*
X656598Y-160747D01*
X655506Y-159581D01*
X653978Y-158998D01*
X652449Y-159289D01*
X651139Y-160164D01*
X650266Y-162206D01*
X649829Y-163956D01*
Y-165706D01*
X650266Y-167456D01*
X651358Y-169206D01*
X652668Y-170372D01*
X654196Y-170664D01*
X655724Y-170081D01*
X657253Y-168331D01*
G01X671041Y-170664D02*
Y-153164D01*
G01X839441Y-215664D02*
Y-198164D01*
X836821Y-201664D01*
G01Y-215664D02*
X842061D01*
G01X852793Y-208373D02*
X854321Y-206331D01*
X855631Y-205164D01*
X857378Y-204581D01*
X858906Y-205164D01*
X859998Y-206331D01*
X860871Y-208081D01*
X861089Y-210122D01*
X860871Y-211873D01*
X859998Y-213623D01*
X858687Y-215081D01*
X857159Y-215664D01*
X855413Y-215081D01*
X853884Y-213331D01*
X853011Y-210706D01*
X852793Y-207789D01*
X853229Y-203998D01*
X853884Y-201955D01*
X854976Y-199914D01*
X856504Y-198456D01*
X858033Y-198164D01*
X859561Y-198747D01*
X860653Y-200206D01*
G01X869638Y-212164D02*
X870947Y-214206D01*
X872694Y-215372D01*
X874659Y-215664D01*
X876406Y-215372D01*
X878153Y-213914D01*
X879244Y-212164D01*
X879463Y-210414D01*
X879026Y-208373D01*
X877498Y-206914D01*
X875969Y-206331D01*
X874004D01*
G01X875969D02*
X877279Y-205456D01*
X878371Y-203998D01*
X878808Y-202248D01*
X878371Y-200497D01*
X877279Y-199039D01*
X875314Y-198164D01*
X873349Y-198456D01*
X871384Y-199623D01*
G01X891941Y-215664D02*
Y-198164D01*
X889321Y-201664D01*
G01Y-215664D02*
X894561D01*
G01X909004D02*
X909441Y-211873D01*
X910096Y-208664D01*
X910969Y-205747D01*
X912061Y-202539D01*
X913808Y-198164D01*
X905074D01*
G01X826324Y-170664D02*
Y-153164D01*
X831564D01*
X833311Y-154039D01*
X834621Y-156081D01*
X835058Y-158414D01*
X834621Y-160747D01*
X833529Y-162497D01*
X831564Y-163373D01*
X826324D01*
G01X852994Y-154623D02*
X851684Y-153747D01*
X850156Y-153164D01*
X848409D01*
X846444Y-154039D01*
X844916Y-155497D01*
X843824Y-157248D01*
X842951Y-160164D01*
X842732Y-162789D01*
X843169Y-165414D01*
X843824Y-167164D01*
X845134Y-168914D01*
X846663Y-170081D01*
X848191Y-170664D01*
X849719D01*
X851248Y-170081D01*
X852558Y-169206D01*
X853650Y-168040D01*
G01X867437Y-161331D02*
X868311Y-160456D01*
X868966Y-158998D01*
X869403Y-156955D01*
X868966Y-155206D01*
X868093Y-154039D01*
X866564Y-153164D01*
X860669D01*
Y-170664D01*
X867874D01*
X869403Y-169498D01*
X870276Y-167747D01*
X870713Y-165706D01*
X870276Y-163664D01*
X868966Y-161914D01*
X867437Y-161331D01*
X860669D01*
G01X876641Y-176497D02*
X889741D01*
G01X895669Y-170664D02*
Y-153164D01*
X905713Y-170664D01*
Y-153164D01*
G01X918191Y-170664D02*
X916444Y-170372D01*
X914916Y-169206D01*
X913606Y-167456D01*
X912732Y-165414D01*
X912296Y-163081D01*
Y-160747D01*
X912732Y-158414D01*
X913606Y-156372D01*
X914916Y-154623D01*
X916444Y-153456D01*
X918191Y-153164D01*
X919937Y-153456D01*
X921466Y-154623D01*
X922776Y-156372D01*
X923650Y-158414D01*
X924086Y-160747D01*
Y-163081D01*
X923650Y-165414D01*
X922776Y-167456D01*
X921466Y-169206D01*
X919937Y-170372D01*
X918191Y-170664D01*
G01X1000741Y-215664D02*
Y-198164D01*
X998121Y-201664D01*
G01Y-215664D02*
X1003361D01*
G01X969032Y-153164D02*
X974491Y-170664D01*
X979950Y-153164D01*
G01X996358Y-170664D02*
X987624D01*
Y-153164D01*
X996358D01*
G01X992864Y-161622D02*
X987624D01*
G01X1005124Y-170664D02*
Y-153164D01*
X1010583D01*
X1012329Y-154039D01*
X1013421Y-155206D01*
X1013858Y-157539D01*
X1013421Y-159873D01*
X1012111Y-161331D01*
X1010583Y-162206D01*
X1005124D01*
G01X1010583D02*
X1013858Y-170664D01*
G01X1026991Y-171247D02*
X1026554Y-170956D01*
Y-170372D01*
X1026991Y-170081D01*
X1027428Y-170372D01*
Y-170956D01*
X1026991Y-171247D01*
G01X1181308Y-198164D02*
Y-215664D01*
X1172574D01*
G01X1164244Y-213040D02*
X1162935Y-214498D01*
X1161406Y-215372D01*
X1159441Y-215664D01*
X1157476Y-215081D01*
X1155948Y-213914D01*
X1154856Y-211873D01*
X1154638Y-209539D01*
X1155074Y-207206D01*
X1156166Y-205747D01*
X1157695Y-204581D01*
X1159223Y-204289D01*
X1160751Y-204581D01*
X1162716Y-205747D01*
X1162061Y-198164D01*
X1156166D01*
G01X1147400D02*
X1141941Y-215664D01*
X1136482Y-198164D01*
G01X1119638Y-199623D02*
X1120948Y-198747D01*
X1122476Y-198164D01*
X1124223D01*
X1126188Y-199039D01*
X1127716Y-200497D01*
X1128808Y-202248D01*
X1129681Y-205164D01*
X1129900Y-207789D01*
X1129463Y-210414D01*
X1128808Y-212164D01*
X1127498Y-213914D01*
X1125969Y-215081D01*
X1124441Y-215664D01*
X1122913D01*
X1121384Y-215081D01*
X1120074Y-214206D01*
X1118982Y-213040D01*
G01X1102138Y-199623D02*
X1103448Y-198747D01*
X1104976Y-198164D01*
X1106723D01*
X1108688Y-199039D01*
X1110216Y-200497D01*
X1111308Y-202248D01*
X1112181Y-205164D01*
X1112400Y-207789D01*
X1111963Y-210414D01*
X1111308Y-212164D01*
X1109998Y-213914D01*
X1108469Y-215081D01*
X1106941Y-215664D01*
X1105413D01*
X1103884Y-215081D01*
X1102574Y-214206D01*
X1101482Y-213040D01*
G01X1102574Y-153164D02*
Y-170664D01*
X1111308D01*
G01X1128371D02*
Y-158998D01*
G01Y-161039D02*
X1127498Y-159873D01*
X1126187Y-159289D01*
X1124659Y-158998D01*
X1123131Y-159581D01*
X1121821Y-160747D01*
X1120947Y-162497D01*
X1120511Y-164831D01*
X1120947Y-167164D01*
X1121821Y-168914D01*
X1123131Y-170081D01*
X1124659Y-170664D01*
X1126187Y-170372D01*
X1127498Y-169498D01*
X1128371Y-168331D01*
G01X1137356Y-175914D02*
X1138666Y-176497D01*
X1140413Y-175914D01*
X1141504Y-174748D01*
X1142378Y-173289D01*
X1143687Y-168623D01*
X1146526Y-158998D01*
G01X1139539D02*
X1143687Y-168623D01*
G01X1156166Y-162789D02*
X1163153D01*
X1162498Y-160747D01*
X1161406Y-159581D01*
X1159878Y-158998D01*
X1158349Y-159289D01*
X1157039Y-160164D01*
X1156166Y-162206D01*
X1155729Y-163956D01*
Y-165706D01*
X1156166Y-167456D01*
X1157258Y-169206D01*
X1158568Y-170372D01*
X1160096Y-170664D01*
X1161624Y-170081D01*
X1163153Y-168331D01*
G01X1173884Y-170664D02*
Y-158998D01*
G01Y-161331D02*
X1174976Y-160164D01*
X1176068Y-159289D01*
X1177596Y-158998D01*
X1178687Y-159289D01*
X1179998Y-160164D01*
G01X1244688Y-170664D02*
Y-153164D01*
X1249054D01*
X1250801Y-154039D01*
X1252111Y-155206D01*
X1253203Y-156955D01*
X1254076Y-158998D01*
X1254294Y-161914D01*
X1254076Y-164831D01*
X1253203Y-166873D01*
X1252111Y-168623D01*
X1250801Y-169789D01*
X1249054Y-170664D01*
X1244688D01*
G01X1263716Y-162789D02*
X1270703D01*
X1270048Y-160747D01*
X1268956Y-159581D01*
X1267428Y-158998D01*
X1265899Y-159289D01*
X1264589Y-160164D01*
X1263716Y-162206D01*
X1263279Y-163956D01*
Y-165706D01*
X1263716Y-167456D01*
X1264808Y-169206D01*
X1266118Y-170372D01*
X1267646Y-170664D01*
X1269174Y-170081D01*
X1270703Y-168331D01*
G01X1281216Y-168623D02*
X1282308Y-169789D01*
X1283836Y-170664D01*
X1285146D01*
X1286456Y-170081D01*
X1287329Y-169206D01*
X1287766Y-168040D01*
X1287548Y-166289D01*
X1286674Y-165414D01*
X1282744Y-163664D01*
X1281871Y-161622D01*
X1282308Y-160164D01*
X1283181Y-159289D01*
X1284491Y-158998D01*
X1285801Y-159289D01*
X1287111Y-160164D01*
G01X1301991Y-158998D02*
Y-170664D01*
G01Y-154331D02*
X1301554Y-154039D01*
Y-153456D01*
X1301991Y-153164D01*
X1302428Y-153456D01*
Y-154039D01*
X1301991Y-154331D01*
G01X1316434Y-175039D02*
X1317963Y-176206D01*
X1319709Y-176497D01*
X1321237Y-176206D01*
X1322548Y-174748D01*
X1323421Y-172706D01*
Y-158998D01*
G01Y-161331D02*
X1322548Y-160164D01*
X1321237Y-159289D01*
X1319709Y-158998D01*
X1317963Y-159581D01*
X1316871Y-160747D01*
X1315997Y-162789D01*
X1315561Y-164831D01*
X1315779Y-166581D01*
X1316653Y-168623D01*
X1317963Y-170081D01*
X1319709Y-170664D01*
X1321019Y-170372D01*
X1322548Y-169206D01*
X1323421Y-168040D01*
G01X1333279Y-170664D02*
Y-158998D01*
G01Y-161914D02*
X1334153Y-160456D01*
X1335463Y-159289D01*
X1337209Y-158998D01*
X1338737Y-159289D01*
X1340048Y-160456D01*
X1340703Y-162497D01*
Y-170664D01*
G01X1351216Y-162789D02*
X1358203D01*
X1357548Y-160747D01*
X1356456Y-159581D01*
X1354928Y-158998D01*
X1353399Y-159289D01*
X1352089Y-160164D01*
X1351216Y-162206D01*
X1350779Y-163956D01*
Y-165706D01*
X1351216Y-167456D01*
X1352308Y-169206D01*
X1353618Y-170372D01*
X1355146Y-170664D01*
X1356674Y-170081D01*
X1358203Y-168331D01*
G01X1368934Y-170664D02*
Y-158998D01*
G01Y-161331D02*
X1370026Y-160164D01*
X1371118Y-159289D01*
X1372646Y-158998D01*
X1373737Y-159289D01*
X1375048Y-160164D01*
G01X1266991Y-215664D02*
X1265244Y-215372D01*
X1263716Y-214206D01*
X1262406Y-212456D01*
X1261532Y-210414D01*
X1261096Y-208081D01*
Y-205747D01*
X1261532Y-203414D01*
X1262406Y-201372D01*
X1263716Y-199623D01*
X1265244Y-198456D01*
X1266991Y-198164D01*
X1268737Y-198456D01*
X1270266Y-199623D01*
X1271576Y-201372D01*
X1272450Y-203414D01*
X1272886Y-205747D01*
Y-208081D01*
X1272450Y-210414D01*
X1271576Y-212456D01*
X1270266Y-214206D01*
X1268737Y-215372D01*
X1266991Y-215664D01*
G01X1268737Y-210997D02*
X1271358Y-215664D01*
G01X1279688Y-198164D02*
Y-210706D01*
X1280561Y-213331D01*
X1282308Y-215081D01*
X1284491Y-215664D01*
X1286674Y-215081D01*
X1288421Y-213331D01*
X1289294Y-210706D01*
Y-198164D01*
G01X1299371D02*
X1304611D01*
G01X1301991D02*
Y-215664D01*
G01X1299371D02*
X1304611D01*
G01X1314469D02*
Y-198164D01*
X1324513Y-215664D01*
Y-198164D01*
G01X1341794Y-199623D02*
X1340484Y-198747D01*
X1338956Y-198164D01*
X1337209D01*
X1335244Y-199039D01*
X1333716Y-200497D01*
X1332624Y-202248D01*
X1331751Y-205164D01*
X1331532Y-207789D01*
X1331969Y-210414D01*
X1332624Y-212164D01*
X1333934Y-213914D01*
X1335463Y-215081D01*
X1336991Y-215664D01*
X1338519D01*
X1340048Y-215081D01*
X1341358Y-214206D01*
X1342450Y-213040D01*
G01X1354491Y-215664D02*
Y-207789D01*
X1350124Y-198164D01*
G01X1358858D02*
X1354491Y-207789D01*
G01X1415691Y-198164D02*
X1413944Y-198747D01*
X1412634Y-200206D01*
X1411761Y-201955D01*
X1411106Y-204289D01*
X1410888Y-206914D01*
X1411106Y-209539D01*
X1411761Y-211873D01*
X1412634Y-213623D01*
X1413944Y-215081D01*
X1415691Y-215664D01*
X1417437Y-215081D01*
X1418748Y-213623D01*
X1419621Y-211873D01*
X1420276Y-209539D01*
X1420494Y-206914D01*
X1420276Y-204289D01*
X1419621Y-201955D01*
X1418748Y-200206D01*
X1417437Y-198747D01*
X1415691Y-198164D01*
G01X1429043Y-208373D02*
X1430571Y-206331D01*
X1431881Y-205164D01*
X1433628Y-204581D01*
X1435156Y-205164D01*
X1436248Y-206331D01*
X1437121Y-208081D01*
X1437339Y-210122D01*
X1437121Y-211873D01*
X1436248Y-213623D01*
X1434937Y-215081D01*
X1433409Y-215664D01*
X1431663Y-215081D01*
X1430134Y-213331D01*
X1429261Y-210706D01*
X1429043Y-207789D01*
X1429479Y-203998D01*
X1430134Y-201955D01*
X1431226Y-199914D01*
X1432754Y-198456D01*
X1434283Y-198164D01*
X1435811Y-198747D01*
X1436903Y-200206D01*
G01X1446761Y-216247D02*
X1454621Y-198164D01*
G01X1468191D02*
X1466444Y-198747D01*
X1465134Y-200206D01*
X1464261Y-201955D01*
X1463606Y-204289D01*
X1463388Y-206914D01*
X1463606Y-209539D01*
X1464261Y-211873D01*
X1465134Y-213623D01*
X1466444Y-215081D01*
X1468191Y-215664D01*
X1469937Y-215081D01*
X1471248Y-213623D01*
X1472121Y-211873D01*
X1472776Y-209539D01*
X1472994Y-206914D01*
X1472776Y-204289D01*
X1472121Y-201955D01*
X1471248Y-200206D01*
X1469937Y-198747D01*
X1468191Y-198164D01*
G01X1481979Y-213623D02*
X1483508Y-215081D01*
X1485254Y-215664D01*
X1487001Y-215081D01*
X1488529Y-213331D01*
X1489621Y-210706D01*
X1490058Y-208081D01*
Y-204873D01*
X1489621Y-202248D01*
X1488529Y-199914D01*
X1487219Y-198747D01*
X1485691Y-198164D01*
X1483944Y-198747D01*
X1482634Y-199914D01*
X1481761Y-201664D01*
X1481324Y-203998D01*
X1481761Y-206039D01*
X1482853Y-208081D01*
X1484163Y-209248D01*
X1485691Y-209539D01*
X1487437Y-208956D01*
X1488748Y-207497D01*
X1490058Y-204873D01*
G01X1499261Y-216247D02*
X1507121Y-198164D01*
G01X1516543Y-201081D02*
X1517853Y-199331D01*
X1519381Y-198456D01*
X1521128Y-198164D01*
X1523311Y-198747D01*
X1524839Y-200206D01*
X1525276Y-201955D01*
X1525058Y-203706D01*
X1524184Y-205164D01*
X1519818Y-208081D01*
X1517853Y-210122D01*
X1516543Y-213040D01*
X1516106Y-215664D01*
X1525276D01*
G01X1538191Y-198164D02*
X1536444Y-198747D01*
X1535134Y-200206D01*
X1534261Y-201955D01*
X1533606Y-204289D01*
X1533388Y-206914D01*
X1533606Y-209539D01*
X1534261Y-211873D01*
X1535134Y-213623D01*
X1536444Y-215081D01*
X1538191Y-215664D01*
X1539937Y-215081D01*
X1541248Y-213623D01*
X1542121Y-211873D01*
X1542776Y-209539D01*
X1542994Y-206914D01*
X1542776Y-204289D01*
X1542121Y-201955D01*
X1541248Y-200206D01*
X1539937Y-198747D01*
X1538191Y-198164D01*
G01X1555691Y-215664D02*
Y-198164D01*
X1553071Y-201664D01*
G01Y-215664D02*
X1558311D01*
G01X1572754D02*
X1573191Y-211873D01*
X1573846Y-208664D01*
X1574719Y-205747D01*
X1575811Y-202539D01*
X1577558Y-198164D01*
X1568824D01*
G01X1463388Y-170664D02*
Y-153164D01*
X1467754D01*
X1469501Y-154039D01*
X1470811Y-155206D01*
X1471903Y-156955D01*
X1472776Y-158998D01*
X1472994Y-161914D01*
X1472776Y-164831D01*
X1471903Y-166873D01*
X1470811Y-168623D01*
X1469501Y-169789D01*
X1467754Y-170664D01*
X1463388D01*
G01X1489621D02*
Y-158998D01*
G01Y-161039D02*
X1488748Y-159873D01*
X1487437Y-159289D01*
X1485909Y-158998D01*
X1484381Y-159581D01*
X1483071Y-160747D01*
X1482197Y-162497D01*
X1481761Y-164831D01*
X1482197Y-167164D01*
X1483071Y-168914D01*
X1484381Y-170081D01*
X1485909Y-170664D01*
X1487437Y-170372D01*
X1488748Y-169498D01*
X1489621Y-168331D01*
G01X1503191Y-153164D02*
Y-170664D01*
G01X1500134Y-158998D02*
X1506248D01*
G01X1517416Y-162789D02*
X1524403D01*
X1523748Y-160747D01*
X1522656Y-159581D01*
X1521128Y-158998D01*
X1519599Y-159289D01*
X1518289Y-160164D01*
X1517416Y-162206D01*
X1516979Y-163956D01*
Y-165706D01*
X1517416Y-167456D01*
X1518508Y-169206D01*
X1519818Y-170372D01*
X1521346Y-170664D01*
X1522874Y-170081D01*
X1524403Y-168331D01*
M02*
